(kicad_sch
	(version 20250114)
	(generator "eeschema")
	(generator_version "9.0")
	(paper "A3")
	(title_block
		(title "PolarFire SoM")
		(date "2025-07-22")
		(rev "1.1.4")
		(company "Antmicro Ltd")
		(comment 1 "www.antmicro.com")
	)
	(bus_alias "UART"
		(members "TX" "RX")
	)
	(bus_alias "USB"
		(members "D_P" "D_N")
	)
	(text "WiFI and Bluetooth Module"
		(exclude_from_sim no)
		(at 15.24 21.59 0)
		(effects
			(font
				(size 4 4)
				(thickness 0.8)
				(bold yes)
			)
			(justify left bottom)
		)
	)
	(text "Decoupling"
		(exclude_from_sim no)
		(at 177.8 214.63 0)
		(effects
			(font
				(size 4 4)
				(thickness 0.8)
				(bold yes)
			)
			(justify left bottom)
		)
	)
	(text "WL and BT Enable"
		(exclude_from_sim no)
		(at 97.79 214.63 0)
		(effects
			(font
				(size 4 4)
				(thickness 0.8)
				(bold yes)
			)
			(justify left bottom)
		)
	)
	(text "Config"
		(exclude_from_sim no)
		(at 245.745 215.265 0)
		(effects
			(font
				(size 4 4)
				(thickness 0.8)
				(bold yes)
			)
			(justify left bottom)
		)
	)
	(text "Sleep clock"
		(exclude_from_sim no)
		(at 38.1 214.63 0)
		(effects
			(font
				(size 4 4)
				(thickness 0.8)
				(bold yes)
			)
			(justify left bottom)
		)
	)
	(junction
		(at 177.8 87.63)
		(diameter 0)
		(color 0 0 0 0)
	)
	(junction
		(at 265.43 243.84)
		(diameter 0)
		(color 0 0 0 0)
	)
	(junction
		(at 35.56 240.03)
		(diameter 0)
		(color 0 0 0 0)
	)
	(junction
		(at 209.55 237.49)
		(diameter 0)
		(color 0 0 0 0)
	)
	(junction
		(at 45.72 233.68)
		(diameter 0)
		(color 0 0 0 0)
	)
	(junction
		(at 130.81 234.95)
		(diameter 0)
		(color 0 0 0 0)
	)
	(junction
		(at 250.19 243.84)
		(diameter 0)
		(color 0 0 0 0)
	)
	(junction
		(at 186.69 237.49)
		(diameter 0)
		(color 0 0 0 0)
	)
	(junction
		(at 35.56 232.41)
		(diameter 0)
		(color 0 0 0 0)
	)
	(junction
		(at 177.8 229.87)
		(diameter 0)
		(color 0 0 0 0)
	)
	(junction
		(at 257.81 243.84)
		(diameter 0)
		(color 0 0 0 0)
	)
	(junction
		(at 121.92 232.41)
		(diameter 0)
		(color 0 0 0 0)
	)
	(junction
		(at 158.75 92.71)
		(diameter 0)
		(color 0 0 0 0)
	)
	(junction
		(at 200.66 229.87)
		(diameter 0)
		(color 0 0 0 0)
	)
	(junction
		(at 177.8 85.09)
		(diameter 0)
		(color 0 0 0 0)
	)
	(no_connect
		(at 226.06 135.89)
	)
	(bus_entry
		(at 171.45 128.27)
		(size -2.54 -2.54)
		(stroke
			(width 0)
			(type default)
		)
	)
	(bus_entry
		(at 171.45 149.86)
		(size -2.54 -2.54)
		(stroke
			(width 0)
			(type default)
		)
	)
	(bus_entry
		(at 171.45 139.7)
		(size -2.54 -2.54)
		(stroke
			(width 0)
			(type default)
		)
	)
	(bus_entry
		(at 248.92 130.81)
		(size -2.54 2.54)
		(stroke
			(width 0)
			(type default)
		)
	)
	(bus_entry
		(at 248.92 128.27)
		(size -2.54 2.54)
		(stroke
			(width 0)
			(type default)
		)
	)
	(bus_entry
		(at 171.45 144.78)
		(size -2.54 -2.54)
		(stroke
			(width 0)
			(type default)
		)
	)
	(bus_entry
		(at 171.45 133.35)
		(size -2.54 -2.54)
		(stroke
			(width 0)
			(type default)
		)
	)
	(bus_entry
		(at 171.45 152.4)
		(size -2.54 -2.54)
		(stroke
			(width 0)
			(type default)
		)
	)
	(bus_entry
		(at 171.45 142.24)
		(size -2.54 -2.54)
		(stroke
			(width 0)
			(type default)
		)
	)
	(bus_entry
		(at 171.45 147.32)
		(size -2.54 -2.54)
		(stroke
			(width 0)
			(type default)
		)
	)
	(wire
		(pts
			(xy 228.6 152.4) (xy 228.6 154.94)
		)
		(stroke
			(width 0)
			(type default)
		)
	)
	(wire
		(pts
			(xy 246.38 243.84) (xy 250.19 243.84)
		)
		(stroke
			(width 0)
			(type default)
		)
	)
	(wire
		(pts
			(xy 226.06 113.03) (xy 233.68 113.03)
		)
		(stroke
			(width 0)
			(type default)
		)
	)
	(wire
		(pts
			(xy 226.06 102.87) (xy 233.68 102.87)
		)
		(stroke
			(width 0)
			(type default)
		)
	)
	(bus
		(pts
			(xy 168.91 135.89) (xy 168.91 137.16)
		)
		(stroke
			(width 0)
			(type default)
		)
	)
	(wire
		(pts
			(xy 257.81 241.3) (xy 257.81 243.84)
		)
		(stroke
			(width 0)
			(type default)
		)
	)
	(bus
		(pts
			(xy 168.91 137.16) (xy 168.91 139.7)
		)
		(stroke
			(width 0)
			(type default)
		)
	)
	(wire
		(pts
			(xy 171.45 142.24) (xy 187.96 142.24)
		)
		(stroke
			(width 0)
			(type default)
		)
	)
	(wire
		(pts
			(xy 233.68 127) (xy 226.06 127)
		)
		(stroke
			(width 0)
			(type default)
		)
	)
	(bus
		(pts
			(xy 168.91 144.78) (xy 168.91 147.32)
		)
		(stroke
			(width 0)
			(type default)
		)
	)
	(wire
		(pts
			(xy 187.96 121.92) (xy 180.34 121.92)
		)
		(stroke
			(width 0)
			(type default)
		)
	)
	(wire
		(pts
			(xy 35.56 232.41) (xy 45.72 232.41)
		)
		(stroke
			(width 0)
			(type default)
		)
	)
	(wire
		(pts
			(xy 158.75 92.71) (xy 158.75 90.17)
		)
		(stroke
			(width 0)
			(type default)
		)
	)
	(wire
		(pts
			(xy 130.81 224.79) (xy 130.81 226.06)
		)
		(stroke
			(width 0)
			(type default)
		)
	)
	(wire
		(pts
			(xy 177.8 229.87) (xy 177.8 231.14)
		)
		(stroke
			(width 0)
			(type default)
		)
	)
	(wire
		(pts
			(xy 186.69 237.49) (xy 186.69 238.76)
		)
		(stroke
			(width 0)
			(type default)
		)
	)
	(wire
		(pts
			(xy 177.8 228.6) (xy 177.8 229.87)
		)
		(stroke
			(width 0)
			(type default)
		)
	)
	(bus
		(pts
			(xy 168.91 147.32) (xy 168.91 149.86)
		)
		(stroke
			(width 0)
			(type default)
		)
	)
	(wire
		(pts
			(xy 265.43 232.41) (xy 265.43 236.22)
		)
		(stroke
			(width 0)
			(type default)
		)
	)
	(wire
		(pts
			(xy 180.34 119.38) (xy 187.96 119.38)
		)
		(stroke
			(width 0)
			(type default)
		)
	)
	(wire
		(pts
			(xy 187.96 99.06) (xy 185.42 99.06)
		)
		(stroke
			(width 0)
			(type default)
		)
	)
	(wire
		(pts
			(xy 200.66 229.87) (xy 200.66 231.14)
		)
		(stroke
			(width 0)
			(type default)
		)
	)
	(wire
		(pts
			(xy 226.06 95.25) (xy 233.68 95.25)
		)
		(stroke
			(width 0)
			(type default)
		)
	)
	(wire
		(pts
			(xy 45.72 232.41) (xy 45.72 233.68)
		)
		(stroke
			(width 0)
			(type default)
		)
	)
	(wire
		(pts
			(xy 35.56 240.03) (xy 35.56 241.3)
		)
		(stroke
			(width 0)
			(type default)
		)
	)
	(wire
		(pts
			(xy 180.34 124.46) (xy 187.96 124.46)
		)
		(stroke
			(width 0)
			(type default)
		)
	)
	(wire
		(pts
			(xy 237.49 142.24) (xy 226.06 142.24)
		)
		(stroke
			(width 0)
			(type default)
		)
	)
	(wire
		(pts
			(xy 250.19 243.84) (xy 257.81 243.84)
		)
		(stroke
			(width 0)
			(type default)
		)
	)
	(wire
		(pts
			(xy 180.34 130.81) (xy 187.96 130.81)
		)
		(stroke
			(width 0)
			(type default)
		)
	)
	(wire
		(pts
			(xy 177.8 80.01) (xy 177.8 85.09)
		)
		(stroke
			(width 0)
			(type default)
		)
	)
	(wire
		(pts
			(xy 187.96 144.78) (xy 171.45 144.78)
		)
		(stroke
			(width 0)
			(type default)
		)
	)
	(wire
		(pts
			(xy 171.45 152.4) (xy 187.96 152.4)
		)
		(stroke
			(width 0)
			(type default)
		)
	)
	(wire
		(pts
			(xy 238.76 227.33) (xy 250.19 227.33)
		)
		(stroke
			(width 0)
			(type default)
		)
	)
	(wire
		(pts
			(xy 177.8 85.09) (xy 187.96 85.09)
		)
		(stroke
			(width 0)
			(type default)
		)
	)
	(wire
		(pts
			(xy 265.43 243.84) (xy 273.05 243.84)
		)
		(stroke
			(width 0)
			(type default)
		)
	)
	(wire
		(pts
			(xy 226.06 144.78) (xy 237.49 144.78)
		)
		(stroke
			(width 0)
			(type default)
		)
	)
	(wire
		(pts
			(xy 226.06 133.35) (xy 246.38 133.35)
		)
		(stroke
			(width 0)
			(type default)
		)
	)
	(wire
		(pts
			(xy 158.75 90.17) (xy 166.37 90.17)
		)
		(stroke
			(width 0)
			(type default)
		)
	)
	(wire
		(pts
			(xy 177.8 237.49) (xy 186.69 237.49)
		)
		(stroke
			(width 0)
			(type default)
		)
	)
	(wire
		(pts
			(xy 226.06 107.95) (xy 233.68 107.95)
		)
		(stroke
			(width 0)
			(type default)
		)
	)
	(wire
		(pts
			(xy 67.31 233.68) (xy 77.47 233.68)
		)
		(stroke
			(width 0)
			(type default)
		)
	)
	(wire
		(pts
			(xy 130.81 241.3) (xy 130.81 242.57)
		)
		(stroke
			(width 0)
			(type default)
		)
	)
	(wire
		(pts
			(xy 35.56 238.76) (xy 35.56 240.03)
		)
		(stroke
			(width 0)
			(type default)
		)
	)
	(wire
		(pts
			(xy 171.45 133.35) (xy 187.96 133.35)
		)
		(stroke
			(width 0)
			(type default)
		)
	)
	(bus
		(pts
			(xy 167.64 134.62) (xy 168.91 135.89)
		)
		(stroke
			(width 0)
			(type default)
		)
	)
	(bus
		(pts
			(xy 168.91 125.73) (xy 168.91 130.81)
		)
		(stroke
			(width 0)
			(type default)
		)
	)
	(wire
		(pts
			(xy 233.68 121.92) (xy 226.06 121.92)
		)
		(stroke
			(width 0)
			(type default)
		)
	)
	(wire
		(pts
			(xy 185.42 101.6) (xy 187.96 101.6)
		)
		(stroke
			(width 0)
			(type default)
		)
	)
	(bus
		(pts
			(xy 248.92 127) (xy 248.92 128.27)
		)
		(stroke
			(width 0)
			(type default)
		)
	)
	(wire
		(pts
			(xy 186.69 229.87) (xy 186.69 231.14)
		)
		(stroke
			(width 0)
			(type default)
		)
	)
	(wire
		(pts
			(xy 233.68 116.84) (xy 226.06 116.84)
		)
		(stroke
			(width 0)
			(type default)
		)
	)
	(wire
		(pts
			(xy 226.06 138.43) (xy 238.76 138.43)
		)
		(stroke
			(width 0)
			(type default)
		)
	)
	(wire
		(pts
			(xy 250.19 227.33) (xy 250.19 236.22)
		)
		(stroke
			(width 0)
			(type default)
		)
	)
	(wire
		(pts
			(xy 130.81 234.95) (xy 130.81 236.22)
		)
		(stroke
			(width 0)
			(type default)
		)
	)
	(wire
		(pts
			(xy 252.73 91.44) (xy 252.73 92.71)
		)
		(stroke
			(width 0)
			(type default)
		)
	)
	(wire
		(pts
			(xy 177.8 229.87) (xy 186.69 229.87)
		)
		(stroke
			(width 0)
			(type default)
		)
	)
	(wire
		(pts
			(xy 172.72 106.68) (xy 187.96 106.68)
		)
		(stroke
			(width 0)
			(type default)
		)
	)
	(wire
		(pts
			(xy 226.06 124.46) (xy 233.68 124.46)
		)
		(stroke
			(width 0)
			(type default)
		)
	)
	(wire
		(pts
			(xy 200.66 237.49) (xy 209.55 237.49)
		)
		(stroke
			(width 0)
			(type default)
		)
	)
	(wire
		(pts
			(xy 171.45 147.32) (xy 187.96 147.32)
		)
		(stroke
			(width 0)
			(type default)
		)
	)
	(wire
		(pts
			(xy 171.45 90.17) (xy 187.96 90.17)
		)
		(stroke
			(width 0)
			(type default)
		)
	)
	(wire
		(pts
			(xy 238.76 232.41) (xy 265.43 232.41)
		)
		(stroke
			(width 0)
			(type default)
		)
	)
	(wire
		(pts
			(xy 45.72 233.68) (xy 48.26 233.68)
		)
		(stroke
			(width 0)
			(type default)
		)
	)
	(wire
		(pts
			(xy 209.55 231.14) (xy 209.55 229.87)
		)
		(stroke
			(width 0)
			(type default)
		)
	)
	(wire
		(pts
			(xy 48.26 236.22) (xy 45.72 236.22)
		)
		(stroke
			(width 0)
			(type default)
		)
	)
	(wire
		(pts
			(xy 186.69 236.22) (xy 186.69 237.49)
		)
		(stroke
			(width 0)
			(type default)
		)
	)
	(wire
		(pts
			(xy 35.56 232.41) (xy 35.56 233.68)
		)
		(stroke
			(width 0)
			(type default)
		)
	)
	(wire
		(pts
			(xy 226.06 130.81) (xy 246.38 130.81)
		)
		(stroke
			(width 0)
			(type default)
		)
	)
	(wire
		(pts
			(xy 200.66 229.87) (xy 209.55 229.87)
		)
		(stroke
			(width 0)
			(type default)
		)
	)
	(wire
		(pts
			(xy 257.81 229.87) (xy 257.81 236.22)
		)
		(stroke
			(width 0)
			(type default)
		)
	)
	(wire
		(pts
			(xy 130.81 231.14) (xy 130.81 234.95)
		)
		(stroke
			(width 0)
			(type default)
		)
	)
	(wire
		(pts
			(xy 177.8 87.63) (xy 187.96 87.63)
		)
		(stroke
			(width 0)
			(type default)
		)
	)
	(wire
		(pts
			(xy 121.92 241.3) (xy 121.92 242.57)
		)
		(stroke
			(width 0)
			(type default)
		)
	)
	(wire
		(pts
			(xy 238.76 234.95) (xy 273.05 234.95)
		)
		(stroke
			(width 0)
			(type default)
		)
	)
	(bus
		(pts
			(xy 167.64 123.19) (xy 166.37 123.19)
		)
		(stroke
			(width 0)
			(type default)
		)
	)
	(wire
		(pts
			(xy 121.92 232.41) (xy 121.92 236.22)
		)
		(stroke
			(width 0)
			(type default)
		)
	)
	(wire
		(pts
			(xy 177.8 236.22) (xy 177.8 237.49)
		)
		(stroke
			(width 0)
			(type default)
		)
	)
	(wire
		(pts
			(xy 157.48 92.71) (xy 158.75 92.71)
		)
		(stroke
			(width 0)
			(type default)
		)
	)
	(wire
		(pts
			(xy 200.66 228.6) (xy 200.66 229.87)
		)
		(stroke
			(width 0)
			(type default)
		)
	)
	(wire
		(pts
			(xy 35.56 240.03) (xy 45.72 240.03)
		)
		(stroke
			(width 0)
			(type default)
		)
	)
	(wire
		(pts
			(xy 180.34 110.49) (xy 187.96 110.49)
		)
		(stroke
			(width 0)
			(type default)
		)
	)
	(bus
		(pts
			(xy 167.64 134.62) (xy 166.37 134.62)
		)
		(stroke
			(width 0)
			(type default)
		)
	)
	(wire
		(pts
			(xy 158.75 92.71) (xy 158.75 96.52)
		)
		(stroke
			(width 0)
			(type default)
		)
	)
	(wire
		(pts
			(xy 121.92 231.14) (xy 121.92 232.41)
		)
		(stroke
			(width 0)
			(type default)
		)
	)
	(wire
		(pts
			(xy 250.19 241.3) (xy 250.19 243.84)
		)
		(stroke
			(width 0)
			(type default)
		)
	)
	(wire
		(pts
			(xy 171.45 128.27) (xy 187.96 128.27)
		)
		(stroke
			(width 0)
			(type default)
		)
	)
	(wire
		(pts
			(xy 200.66 236.22) (xy 200.66 237.49)
		)
		(stroke
			(width 0)
			(type default)
		)
	)
	(wire
		(pts
			(xy 273.05 243.84) (xy 273.05 241.3)
		)
		(stroke
			(width 0)
			(type default)
		)
	)
	(wire
		(pts
			(xy 238.76 229.87) (xy 257.81 229.87)
		)
		(stroke
			(width 0)
			(type default)
		)
	)
	(bus
		(pts
			(xy 251.46 125.73) (xy 250.19 125.73)
		)
		(stroke
			(width 0)
			(type default)
		)
	)
	(wire
		(pts
			(xy 187.96 139.7) (xy 171.45 139.7)
		)
		(stroke
			(width 0)
			(type default)
		)
	)
	(wire
		(pts
			(xy 241.3 85.09) (xy 246.38 85.09)
		)
		(stroke
			(width 0)
			(type default)
		)
	)
	(bus
		(pts
			(xy 250.19 125.73) (xy 248.92 127)
		)
		(stroke
			(width 0)
			(type default)
		)
	)
	(wire
		(pts
			(xy 228.6 152.4) (xy 226.06 152.4)
		)
		(stroke
			(width 0)
			(type default)
		)
	)
	(bus
		(pts
			(xy 168.91 142.24) (xy 168.91 144.78)
		)
		(stroke
			(width 0)
			(type default)
		)
	)
	(wire
		(pts
			(xy 233.68 105.41) (xy 226.06 105.41)
		)
		(stroke
			(width 0)
			(type default)
		)
	)
	(wire
		(pts
			(xy 187.96 116.84) (xy 180.34 116.84)
		)
		(stroke
			(width 0)
			(type default)
		)
	)
	(wire
		(pts
			(xy 243.84 138.43) (xy 246.38 138.43)
		)
		(stroke
			(width 0)
			(type default)
		)
	)
	(wire
		(pts
			(xy 226.06 85.09) (xy 236.22 85.09)
		)
		(stroke
			(width 0)
			(type default)
		)
	)
	(bus
		(pts
			(xy 167.64 123.19) (xy 168.91 124.46)
		)
		(stroke
			(width 0)
			(type default)
		)
	)
	(wire
		(pts
			(xy 180.34 135.89) (xy 187.96 135.89)
		)
		(stroke
			(width 0)
			(type default)
		)
	)
	(wire
		(pts
			(xy 233.68 110.49) (xy 226.06 110.49)
		)
		(stroke
			(width 0)
			(type default)
		)
	)
	(wire
		(pts
			(xy 180.34 113.03) (xy 187.96 113.03)
		)
		(stroke
			(width 0)
			(type default)
		)
	)
	(wire
		(pts
			(xy 187.96 95.25) (xy 177.8 95.25)
		)
		(stroke
			(width 0)
			(type default)
		)
	)
	(wire
		(pts
			(xy 257.81 243.84) (xy 265.43 243.84)
		)
		(stroke
			(width 0)
			(type default)
		)
	)
	(wire
		(pts
			(xy 177.8 87.63) (xy 177.8 95.25)
		)
		(stroke
			(width 0)
			(type default)
		)
	)
	(wire
		(pts
			(xy 158.75 101.6) (xy 158.75 102.87)
		)
		(stroke
			(width 0)
			(type default)
		)
	)
	(wire
		(pts
			(xy 265.43 243.84) (xy 265.43 241.3)
		)
		(stroke
			(width 0)
			(type default)
		)
	)
	(bus
		(pts
			(xy 248.92 128.27) (xy 248.92 130.81)
		)
		(stroke
			(width 0)
			(type default)
		)
	)
	(wire
		(pts
			(xy 45.72 238.76) (xy 45.72 240.03)
		)
		(stroke
			(width 0)
			(type default)
		)
	)
	(wire
		(pts
			(xy 115.57 234.95) (xy 130.81 234.95)
		)
		(stroke
			(width 0)
			(type default)
		)
	)
	(wire
		(pts
			(xy 35.56 231.14) (xy 35.56 232.41)
		)
		(stroke
			(width 0)
			(type default)
		)
	)
	(wire
		(pts
			(xy 226.06 119.38) (xy 233.68 119.38)
		)
		(stroke
			(width 0)
			(type default)
		)
	)
	(bus
		(pts
			(xy 168.91 124.46) (xy 168.91 125.73)
		)
		(stroke
			(width 0)
			(type default)
		)
	)
	(bus
		(pts
			(xy 168.91 139.7) (xy 168.91 142.24)
		)
		(stroke
			(width 0)
			(type default)
		)
	)
	(wire
		(pts
			(xy 115.57 232.41) (xy 121.92 232.41)
		)
		(stroke
			(width 0)
			(type default)
		)
	)
	(wire
		(pts
			(xy 172.72 104.14) (xy 187.96 104.14)
		)
		(stroke
			(width 0)
			(type default)
		)
	)
	(wire
		(pts
			(xy 209.55 236.22) (xy 209.55 237.49)
		)
		(stroke
			(width 0)
			(type default)
		)
	)
	(wire
		(pts
			(xy 237.49 147.32) (xy 226.06 147.32)
		)
		(stroke
			(width 0)
			(type default)
		)
	)
	(wire
		(pts
			(xy 187.96 149.86) (xy 171.45 149.86)
		)
		(stroke
			(width 0)
			(type default)
		)
	)
	(wire
		(pts
			(xy 177.8 85.09) (xy 177.8 87.63)
		)
		(stroke
			(width 0)
			(type default)
		)
	)
	(wire
		(pts
			(xy 121.92 224.79) (xy 121.92 226.06)
		)
		(stroke
			(width 0)
			(type default)
		)
	)
	(wire
		(pts
			(xy 246.38 138.43) (xy 246.38 139.7)
		)
		(stroke
			(width 0)
			(type default)
		)
	)
	(wire
		(pts
			(xy 273.05 234.95) (xy 273.05 236.22)
		)
		(stroke
			(width 0)
			(type default)
		)
	)
	(wire
		(pts
			(xy 237.49 100.33) (xy 226.06 100.33)
		)
		(stroke
			(width 0)
			(type default)
		)
	)
	(wire
		(pts
			(xy 209.55 237.49) (xy 209.55 238.76)
		)
		(stroke
			(width 0)
			(type default)
		)
	)
	(wire
		(pts
			(xy 45.72 236.22) (xy 45.72 233.68)
		)
		(stroke
			(width 0)
			(type default)
		)
	)
	(wire
		(pts
			(xy 48.26 238.76) (xy 45.72 238.76)
		)
		(stroke
			(width 0)
			(type default)
		)
	)
	(wire
		(pts
			(xy 158.75 92.71) (xy 187.96 92.71)
		)
		(stroke
			(width 0)
			(type default)
		)
	)
	(label "STRAP_0"
		(at 237.49 142.24 180)
		(effects
			(font
				(size 1.27 1.27)
			)
			(justify right bottom)
		)
	)
	(label "PF_BT.RX"
		(at 171.45 133.35 0)
		(effects
			(font
				(size 1.27 1.27)
			)
			(justify left bottom)
		)
	)
	(label "WL_BT.D_P"
		(at 234.315 130.81 0)
		(effects
			(font
				(size 1.27 1.27)
			)
			(justify left bottom)
		)
	)
	(label "WiFi.CMD"
		(at 171.45 139.7 0)
		(effects
			(font
				(size 1.27 1.27)
			)
			(justify left bottom)
		)
	)
	(label "STRAP_1"
		(at 237.49 144.78 180)
		(effects
			(font
				(size 1.27 1.27)
			)
			(justify right bottom)
		)
	)
	(label "STRAP_2"
		(at 238.76 232.41 0)
		(effects
			(font
				(size 1.27 1.27)
			)
			(justify left bottom)
		)
	)
	(label "PF_BT.TX"
		(at 171.45 128.27 0)
		(effects
			(font
				(size 1.27 1.27)
			)
			(justify left bottom)
		)
	)
	(label "WiFi.DAT1"
		(at 171.45 144.78 0)
		(effects
			(font
				(size 1.27 1.27)
			)
			(justify left bottom)
		)
	)
	(label "STRAP_1"
		(at 238.76 229.87 0)
		(effects
			(font
				(size 1.27 1.27)
			)
			(justify left bottom)
		)
	)
	(label "STRAP_0"
		(at 238.76 227.33 0)
		(effects
			(font
				(size 1.27 1.27)
			)
			(justify left bottom)
		)
	)
	(label "WiFi.DAT0"
		(at 171.45 142.24 0)
		(effects
			(font
				(size 1.27 1.27)
			)
			(justify left bottom)
		)
	)
	(label "LPO_IN"
		(at 77.47 233.68 180)
		(effects
			(font
				(size 1.27 1.27)
			)
			(justify right bottom)
		)
	)
	(label "WiFi.DAT3"
		(at 171.45 149.86 0)
		(effects
			(font
				(size 1.27 1.27)
			)
			(justify left bottom)
		)
	)
	(label "WiFi.CLK"
		(at 171.45 152.4 0)
		(effects
			(font
				(size 1.27 1.27)
			)
			(justify left bottom)
		)
	)
	(label "LPO_IN"
		(at 172.72 106.68 0)
		(effects
			(font
				(size 1.27 1.27)
			)
			(justify left bottom)
		)
	)
	(label "WL_BT.D_N"
		(at 234.315 133.35 0)
		(effects
			(font
				(size 1.27 1.27)
			)
			(justify left bottom)
		)
	)
	(label "JTAG_SEL"
		(at 238.76 234.95 0)
		(effects
			(font
				(size 1.27 1.27)
			)
			(justify left bottom)
		)
	)
	(label "STRAP_2"
		(at 237.49 147.32 180)
		(effects
			(font
				(size 1.27 1.27)
			)
			(justify right bottom)
		)
	)
	(label "JTAG_SEL"
		(at 237.49 100.33 180)
		(effects
			(font
				(size 1.27 1.27)
			)
			(justify right bottom)
		)
	)
	(label "WiFi.DAT2"
		(at 171.45 147.32 0)
		(effects
			(font
				(size 1.27 1.27)
			)
			(justify left bottom)
		)
	)
	(global_label "PF_TDO"
		(shape input)
		(at 233.68 105.41 0)
		(fields_autoplaced yes)
		(effects
			(font
				(size 1.27 1.27)
			)
			(justify left)
		)
		(property "Intersheetrefs" "${INTERSHEET_REFS}"
			(at 242.9874 105.4894 0)
			(effects
				(font
					(size 1.27 1.27)
				)
				(justify left)
			)
		)
	)
	(global_label "WL_REG_ON"
		(shape input)
		(at 115.57 232.41 180)
		(fields_autoplaced yes)
		(effects
			(font
				(size 1.27 1.27)
			)
			(justify right)
		)
		(property "Intersheetrefs" "${INTERSHEET_REFS}"
			(at 102.3921 232.4894 0)
			(effects
				(font
					(size 1.27 1.27)
				)
				(justify right)
			)
		)
	)
	(global_label "BT_REG_ON"
		(shape input)
		(at 185.42 99.06 180)
		(fields_autoplaced yes)
		(effects
			(font
				(size 1.27 1.27)
			)
			(justify right)
		)
		(property "Intersheetrefs" "${INTERSHEET_REFS}"
			(at 172.484 98.9806 0)
			(effects
				(font
					(size 1.27 1.27)
				)
				(justify right)
			)
		)
	)
	(global_label "JTAG_RESET_n"
		(shape input)
		(at 233.68 102.87 0)
		(fields_autoplaced yes)
		(effects
			(font
				(size 1.27 1.27)
			)
			(justify left)
		)
		(property "Intersheetrefs" "${INTERSHEET_REFS}"
			(at 249.2164 102.7906 0)
			(effects
				(font
					(size 1.27 1.27)
				)
				(justify left)
			)
		)
	)
	(global_label "JTAG_TCK"
		(shape input)
		(at 233.68 110.49 0)
		(fields_autoplaced yes)
		(effects
			(font
				(size 1.27 1.27)
			)
			(justify left)
		)
		(property "Intersheetrefs" "${INTERSHEET_REFS}"
			(at 244.8621 110.4106 0)
			(effects
				(font
					(size 1.27 1.27)
				)
				(justify left)
			)
		)
	)
	(global_label "WL_REG_ON"
		(shape input)
		(at 185.42 101.6 180)
		(fields_autoplaced yes)
		(effects
			(font
				(size 1.27 1.27)
			)
			(justify right)
		)
		(property "Intersheetrefs" "${INTERSHEET_REFS}"
			(at 172.2421 101.5206 0)
			(effects
				(font
					(size 1.27 1.27)
				)
				(justify right)
			)
		)
	)
	(global_label "JTAG_TMS"
		(shape input)
		(at 233.68 113.03 0)
		(fields_autoplaced yes)
		(effects
			(font
				(size 1.27 1.27)
			)
			(justify left)
		)
		(property "Intersheetrefs" "${INTERSHEET_REFS}"
			(at 244.9831 112.9506 0)
			(effects
				(font
					(size 1.27 1.27)
				)
				(justify left)
			)
		)
	)
	(global_label "BT_REG_ON"
		(shape input)
		(at 115.57 234.95 180)
		(fields_autoplaced yes)
		(effects
			(font
				(size 1.27 1.27)
			)
			(justify right)
		)
		(property "Intersheetrefs" "${INTERSHEET_REFS}"
			(at 102.634 235.0294 0)
			(effects
				(font
					(size 1.27 1.27)
				)
				(justify right)
			)
		)
	)
	(global_label "WL_BT_TDO"
		(shape output)
		(at 233.68 107.95 0)
		(fields_autoplaced yes)
		(effects
			(font
				(size 1.27 1.27)
			)
			(justify left)
		)
		(property "Intersheetrefs" "${INTERSHEET_REFS}"
			(at 246.8856 107.95 0)
			(effects
				(font
					(size 1.27 1.27)
				)
				(justify left)
			)
		)
	)
	(hierarchical_label "WiFi{SDIO}"
		(shape input)
		(at 166.37 134.62 180)
		(effects
			(font
				(size 1.27 1.27)
			)
			(justify right)
		)
	)
	(hierarchical_label "WL_BT{USB}"
		(shape input)
		(at 251.46 125.73 0)
		(effects
			(font
				(size 1.27 1.27)
			)
			(justify left)
		)
	)
	(hierarchical_label "PF_BT{UART}"
		(shape input)
		(at 166.37 123.19 180)
		(effects
			(font
				(size 1.27 1.27)
			)
			(justify right)
		)
	)
	(symbol
		(lib_id "antmicroTestPoints:TP_0.75mm_SMD")
		(at 172.72 104.14 0)
		(mirror y)
		(unit 1)
		(exclude_from_sim no)
		(in_bom no)
		(on_board yes)
		(dnp no)
		(property "Reference" "TP27"
			(at 165.735 104.14 0)
			(effects
				(font
					(size 1.27 1.27)
					(thickness 0.15)
				)
			)
		)
		(property "Value" "TP_0.75mm_SMD"
			(at 161.925 107.95 0)
			(effects
				(font
					(size 1.27 1.27)
					(thickness 0.15)
				)
				(justify left bottom)
				(hide yes)
			)
		)
		(property "Footprint" "antmicro-footprints:TP_SMD_0.75mm"
			(at 161.925 110.49 0)
			(effects
				(font
					(size 1.27 1.27)
					(thickness 0.15)
				)
				(justify left bottom)
				(hide yes)
			)
		)
		(property "Datasheet" ""
			(at 154.94 116.84 0)
			(effects
				(font
					(size 1.27 1.27)
					(thickness 0.15)
				)
				(justify left bottom)
				(hide yes)
			)
		)
		(property "Description" "SMT test point"
			(at 172.72 104.14 0)
			(effects
				(font
					(size 1.27 1.27)
				)
				(hide yes)
			)
		)
		(property "MPN" ""
			(at 161.925 115.57 0)
			(effects
				(font
					(size 1.27 1.27)
					(thickness 0.15)
				)
				(justify left bottom)
				(hide yes)
			)
		)
		(property "Manufacturer" ""
			(at 161.925 110.49 0)
			(effects
				(font
					(size 1.27 1.27)
					(thickness 0.15)
				)
				(justify left bottom)
				(hide yes)
			)
		)
		(property "Author" "Antmicro"
			(at 161.925 113.03 0)
			(effects
				(font
					(size 1.27 1.27)
					(thickness 0.15)
				)
				(justify left bottom)
				(hide yes)
			)
		)
		(property "License" "Apache-2.0"
			(at 161.925 115.57 0)
			(effects
				(font
					(size 1.27 1.27)
					(thickness 0.15)
				)
				(justify left bottom)
				(hide yes)
			)
		)
		(property "Public" "False"
			(at 162.56 118.11 0)
			(effects
				(font
					(size 1.27 1.27)
				)
				(justify left bottom)
				(hide yes)
			)
		)
		(pin "1"
		)
		(instances
			(project "polarfire-som"
				(path ""
					(reference "TP27")
					(unit 1)
				)
			)
		)
	)
	(symbol
		(lib_id "antmicroCapacitors0402:C_10u_0402")
		(at 177.8 236.22 90)
		(unit 1)
		(exclude_from_sim no)
		(in_bom yes)
		(on_board yes)
		(dnp no)
		(property "Reference" "C283"
			(at 179.07 232.41 90)
			(effects
				(font
					(size 1.27 1.27)
					(thickness 0.15)
				)
				(justify right)
			)
		)
		(property "Value" "C_10u_0402"
			(at 187.96 215.9 0)
			(effects
				(font
					(size 1.27 1.27)
					(thickness 0.15)
				)
				(justify left bottom)
				(hide yes)
			)
		)
		(property "Footprint" "antmicro-footprints:C_0402_1005Metric"
			(at 190.5 215.9 0)
			(effects
				(font
					(size 1.27 1.27)
					(thickness 0.15)
				)
				(justify left bottom)
				(hide yes)
			)
		)
		(property "Datasheet" "https://www.yageo.com/en/Chart/Download/pdf/CC0402MRX5R5BB106"
			(at 193.04 215.9 0)
			(effects
				(font
					(size 1.27 1.27)
					(thickness 0.15)
				)
				(justify left bottom)
				(hide yes)
			)
		)
		(property "Description" "SMD Multilayer Ceramic Capacitor, 10 µF, 6.3 V, 0402 [1005 Metric], ± 20%, X5R, CC Series"
			(at 177.8 236.22 0)
			(effects
				(font
					(size 1.27 1.27)
				)
				(hide yes)
			)
		)
		(property "MPN" "CC0402MRX5R5BB106"
			(at 195.58 215.9 0)
			(effects
				(font
					(size 1.27 1.27)
					(thickness 0.15)
				)
				(justify left bottom)
				(hide yes)
			)
		)
		(property "Manufacturer" "YAGEO"
			(at 198.12 215.9 0)
			(effects
				(font
					(size 1.27 1.27)
					(thickness 0.15)
				)
				(justify left bottom)
				(hide yes)
			)
		)
		(property "License" "Apache-2.0"
			(at 200.66 215.9 0)
			(effects
				(font
					(size 1.27 1.27)
					(thickness 0.15)
				)
				(justify left bottom)
				(hide yes)
			)
		)
		(property "Author" "Antmicro"
			(at 203.2 215.9 0)
			(effects
				(font
					(size 1.27 1.27)
					(thickness 0.15)
				)
				(justify left bottom)
				(hide yes)
			)
		)
		(property "Val" "10u"
			(at 182.88 234.95 90)
			(effects
				(font
					(size 1.27 1.27)
					(thickness 0.15)
				)
				(justify left bottom)
			)
		)
		(property "Voltage" ""
			(at 205.74 215.9 0)
			(effects
				(font
					(size 1.27 1.27)
				)
				(justify left bottom)
				(hide yes)
			)
		)
		(property "Dielectric" ""
			(at 208.28 215.9 0)
			(effects
				(font
					(size 1.27 1.27)
				)
				(justify left bottom)
				(hide yes)
			)
		)
		(property "Public" ""
			(at 210.82 215.9 0)
			(effects
				(font
					(size 1.27 1.27)
				)
				(justify left bottom)
				(hide yes)
			)
		)
		(pin "1"
		)
		(pin "2"
		)
		(instances
			(project "polarfire-som"
				(path ""
					(reference "C283")
					(unit 1)
				)
			)
		)
	)
	(symbol
		(lib_id "antmicropower:GND")
		(at 186.69 238.76 0)
		(unit 1)
		(exclude_from_sim no)
		(in_bom yes)
		(on_board yes)
		(dnp no)
		(property "Reference" "#PWR0267"
			(at 195.58 241.3 0)
			(effects
				(font
					(size 1.27 1.27)
					(thickness 0.15)
				)
				(justify left bottom)
				(hide yes)
			)
		)
		(property "Value" "GND"
			(at 186.69 242.57 0)
			(effects
				(font
					(size 1.27 1.27)
					(thickness 0.15)
				)
			)
		)
		(property "Footprint" ""
			(at 195.58 246.38 0)
			(effects
				(font
					(size 1.27 1.27)
					(thickness 0.15)
				)
				(justify left bottom)
				(hide yes)
			)
		)
		(property "Datasheet" ""
			(at 195.58 251.46 0)
			(effects
				(font
					(size 1.27 1.27)
					(thickness 0.15)
				)
				(justify left bottom)
				(hide yes)
			)
		)
		(property "Description" ""
			(at 186.69 238.76 0)
			(effects
				(font
					(size 1.27 1.27)
				)
				(hide yes)
			)
		)
		(property "Author" "Antmicro"
			(at 195.58 246.38 0)
			(effects
				(font
					(size 1.27 1.27)
					(thickness 0.15)
				)
				(justify left bottom)
				(hide yes)
			)
		)
		(property "License" "Apache-2.0"
			(at 195.58 248.92 0)
			(effects
				(font
					(size 1.27 1.27)
					(thickness 0.15)
				)
				(justify left bottom)
				(hide yes)
			)
		)
		(pin "1"
		)
		(instances
			(project "polarfire-som"
				(path ""
					(reference "#PWR0267")
					(unit 1)
				)
			)
		)
	)
	(symbol
		(lib_id "antmicroResistors0402:R_10k_0402")
		(at 130.81 231.14 90)
		(unit 1)
		(exclude_from_sim no)
		(in_bom yes)
		(on_board yes)
		(dnp no)
		(property "Reference" "R147"
			(at 132.08 227.33 90)
			(effects
				(font
					(size 1.27 1.27)
					(thickness 0.15)
				)
				(justify right)
			)
		)
		(property "Value" "R_10k_0402"
			(at 143.51 210.82 0)
			(effects
				(font
					(size 1.27 1.27)
					(thickness 0.15)
				)
				(justify left bottom)
				(hide yes)
			)
		)
		(property "Footprint" "antmicro-footprints:R_0402_1005Metric"
			(at 146.05 210.82 0)
			(effects
				(font
					(size 1.27 1.27)
					(thickness 0.15)
				)
				(justify left bottom)
				(hide yes)
			)
		)
		(property "Datasheet" "https://www.bourns.com/docs/product-datasheets/cr.pdf"
			(at 148.59 210.82 0)
			(effects
				(font
					(size 1.27 1.27)
					(thickness 0.15)
				)
				(justify left bottom)
				(hide yes)
			)
		)
		(property "Description" "SMD Chip Resistor, 10 kohm, ± 1%, 62.5 mW, 0402 [1005 Metric], Thick Film, General Purpose"
			(at 130.81 231.14 0)
			(effects
				(font
					(size 1.27 1.27)
				)
				(hide yes)
			)
		)
		(property "MPN" "CR0402-FX-1002GLF"
			(at 151.13 210.82 0)
			(effects
				(font
					(size 1.27 1.27)
					(thickness 0.15)
				)
				(justify left bottom)
				(hide yes)
			)
		)
		(property "Manufacturer" "Bourns"
			(at 153.67 210.82 0)
			(effects
				(font
					(size 1.27 1.27)
					(thickness 0.15)
				)
				(justify left bottom)
				(hide yes)
			)
		)
		(property "License" "Apache-2.0"
			(at 156.21 210.82 0)
			(effects
				(font
					(size 1.27 1.27)
					(thickness 0.15)
				)
				(justify left bottom)
				(hide yes)
			)
		)
		(property "Author" "Antmicro"
			(at 158.75 210.82 0)
			(effects
				(font
					(size 1.27 1.27)
					(thickness 0.15)
				)
				(justify left bottom)
				(hide yes)
			)
		)
		(property "Val" "10k"
			(at 132.08 229.87 90)
			(effects
				(font
					(size 1.27 1.27)
					(thickness 0.15)
				)
				(justify right)
			)
		)
		(property "Tolerance" "1%"
			(at 140.97 210.82 0)
			(effects
				(font
					(size 1.27 1.27)
				)
				(justify left bottom)
				(hide yes)
			)
		)
		(property "Public" ""
			(at 161.29 210.82 0)
			(effects
				(font
					(size 1.27 1.27)
				)
				(justify left bottom)
				(hide yes)
			)
		)
		(pin "1"
		)
		(pin "2"
		)
		(instances
			(project "polarfire-som"
				(path ""
					(reference "R147")
					(unit 1)
				)
			)
		)
	)
	(symbol
		(lib_id "antmicropower:+3V3")
		(at 121.92 224.79 0)
		(unit 1)
		(exclude_from_sim no)
		(in_bom yes)
		(on_board yes)
		(dnp no)
		(property "Reference" "#PWR0340"
			(at 137.16 227.33 0)
			(effects
				(font
					(size 1.27 1.27)
					(thickness 0.15)
				)
				(justify left bottom)
				(hide yes)
			)
		)
		(property "Value" "+3V3"
			(at 121.92 220.98 0)
			(effects
				(font
					(size 1.27 1.27)
					(thickness 0.15)
				)
			)
		)
		(property "Footprint" ""
			(at 137.16 232.41 0)
			(effects
				(font
					(size 1.27 1.27)
					(thickness 0.15)
				)
				(justify left bottom)
				(hide yes)
			)
		)
		(property "Datasheet" ""
			(at 137.16 234.95 0)
			(effects
				(font
					(size 1.27 1.27)
					(thickness 0.15)
				)
				(justify left bottom)
				(hide yes)
			)
		)
		(property "Description" ""
			(at 121.92 224.79 0)
			(effects
				(font
					(size 1.27 1.27)
				)
				(hide yes)
			)
		)
		(property "Author" "Antmicro"
			(at 137.16 232.41 0)
			(effects
				(font
					(size 1.27 1.27)
					(thickness 0.15)
				)
				(justify left bottom)
				(hide yes)
			)
		)
		(property "License" "Apache-2.0"
			(at 137.16 234.95 0)
			(effects
				(font
					(size 1.27 1.27)
					(thickness 0.15)
				)
				(justify left bottom)
				(hide yes)
			)
		)
		(pin "1"
		)
		(instances
			(project "polarfire-som"
				(path ""
					(reference "#PWR0340")
					(unit 1)
				)
			)
		)
	)
	(symbol
		(lib_id "antmicroTestPoints:TP_0.75mm_SMD")
		(at 180.34 119.38 180)
		(unit 1)
		(exclude_from_sim no)
		(in_bom no)
		(on_board yes)
		(dnp no)
		(property "Reference" "TP14"
			(at 173.355 119.38 0)
			(effects
				(font
					(size 1.27 1.27)
					(thickness 0.15)
				)
			)
		)
		(property "Value" "TP_0.75mm_SMD"
			(at 169.545 115.57 0)
			(effects
				(font
					(size 1.27 1.27)
					(thickness 0.15)
				)
				(justify left bottom)
				(hide yes)
			)
		)
		(property "Footprint" "antmicro-footprints:TP_SMD_0.75mm"
			(at 169.545 113.03 0)
			(effects
				(font
					(size 1.27 1.27)
					(thickness 0.15)
				)
				(justify left bottom)
				(hide yes)
			)
		)
		(property "Datasheet" ""
			(at 162.56 106.68 0)
			(effects
				(font
					(size 1.27 1.27)
					(thickness 0.15)
				)
				(justify left bottom)
				(hide yes)
			)
		)
		(property "Description" "SMT test point"
			(at 180.34 119.38 0)
			(effects
				(font
					(size 1.27 1.27)
				)
				(hide yes)
			)
		)
		(property "MPN" ""
			(at 169.545 107.95 0)
			(effects
				(font
					(size 1.27 1.27)
					(thickness 0.15)
				)
				(justify left bottom)
				(hide yes)
			)
		)
		(property "Manufacturer" ""
			(at 169.545 113.03 0)
			(effects
				(font
					(size 1.27 1.27)
					(thickness 0.15)
				)
				(justify left bottom)
				(hide yes)
			)
		)
		(property "Author" "Antmicro"
			(at 169.545 110.49 0)
			(effects
				(font
					(size 1.27 1.27)
					(thickness 0.15)
				)
				(justify left bottom)
				(hide yes)
			)
		)
		(property "License" "Apache-2.0"
			(at 169.545 107.95 0)
			(effects
				(font
					(size 1.27 1.27)
					(thickness 0.15)
				)
				(justify left bottom)
				(hide yes)
			)
		)
		(property "Public" "False"
			(at 170.18 105.41 0)
			(effects
				(font
					(size 1.27 1.27)
				)
				(justify left bottom)
				(hide yes)
			)
		)
		(pin "1"
		)
		(instances
			(project "polarfire-som"
				(path ""
					(reference "TP14")
					(unit 1)
				)
			)
		)
	)
	(symbol
		(lib_id "antmicroResistors0402:R_10k_0402")
		(at 273.05 241.3 90)
		(unit 1)
		(exclude_from_sim no)
		(in_bom yes)
		(on_board yes)
		(dnp no)
		(property "Reference" "R151"
			(at 274.32 237.49 90)
			(effects
				(font
					(size 1.27 1.27)
					(thickness 0.15)
				)
				(justify right)
			)
		)
		(property "Value" "R_10k_0402"
			(at 285.75 220.98 0)
			(effects
				(font
					(size 1.27 1.27)
					(thickness 0.15)
				)
				(justify left bottom)
				(hide yes)
			)
		)
		(property "Footprint" "antmicro-footprints:R_0402_1005Metric"
			(at 288.29 220.98 0)
			(effects
				(font
					(size 1.27 1.27)
					(thickness 0.15)
				)
				(justify left bottom)
				(hide yes)
			)
		)
		(property "Datasheet" "https://www.bourns.com/docs/product-datasheets/cr.pdf"
			(at 290.83 220.98 0)
			(effects
				(font
					(size 1.27 1.27)
					(thickness 0.15)
				)
				(justify left bottom)
				(hide yes)
			)
		)
		(property "Description" "SMD Chip Resistor, 10 kohm, ± 1%, 62.5 mW, 0402 [1005 Metric], Thick Film, General Purpose"
			(at 273.05 241.3 0)
			(effects
				(font
					(size 1.27 1.27)
				)
				(hide yes)
			)
		)
		(property "MPN" "CR0402-FX-1002GLF"
			(at 293.37 220.98 0)
			(effects
				(font
					(size 1.27 1.27)
					(thickness 0.15)
				)
				(justify left bottom)
				(hide yes)
			)
		)
		(property "Manufacturer" "Bourns"
			(at 295.91 220.98 0)
			(effects
				(font
					(size 1.27 1.27)
					(thickness 0.15)
				)
				(justify left bottom)
				(hide yes)
			)
		)
		(property "License" "Apache-2.0"
			(at 298.45 220.98 0)
			(effects
				(font
					(size 1.27 1.27)
					(thickness 0.15)
				)
				(justify left bottom)
				(hide yes)
			)
		)
		(property "Author" "Antmicro"
			(at 300.99 220.98 0)
			(effects
				(font
					(size 1.27 1.27)
					(thickness 0.15)
				)
				(justify left bottom)
				(hide yes)
			)
		)
		(property "Val" "10k"
			(at 274.32 240.03 90)
			(effects
				(font
					(size 1.27 1.27)
					(thickness 0.15)
				)
				(justify right)
			)
		)
		(property "Tolerance" "1%"
			(at 283.21 220.98 0)
			(effects
				(font
					(size 1.27 1.27)
				)
				(justify left bottom)
				(hide yes)
			)
		)
		(property "Public" ""
			(at 303.53 220.98 0)
			(effects
				(font
					(size 1.27 1.27)
				)
				(justify left bottom)
				(hide yes)
			)
		)
		(pin "1"
		)
		(pin "2"
		)
		(instances
			(project "polarfire-som"
				(path ""
					(reference "R151")
					(unit 1)
				)
			)
		)
	)
	(symbol
		(lib_id "antmicropower:GND")
		(at 121.92 242.57 0)
		(unit 1)
		(exclude_from_sim no)
		(in_bom yes)
		(on_board yes)
		(dnp no)
		(property "Reference" "#PWR0268"
			(at 130.81 245.11 0)
			(effects
				(font
					(size 1.27 1.27)
					(thickness 0.15)
				)
				(justify left bottom)
				(hide yes)
			)
		)
		(property "Value" "GND"
			(at 121.92 246.38 0)
			(effects
				(font
					(size 1.27 1.27)
					(thickness 0.15)
				)
			)
		)
		(property "Footprint" ""
			(at 130.81 250.19 0)
			(effects
				(font
					(size 1.27 1.27)
					(thickness 0.15)
				)
				(justify left bottom)
				(hide yes)
			)
		)
		(property "Datasheet" ""
			(at 130.81 255.27 0)
			(effects
				(font
					(size 1.27 1.27)
					(thickness 0.15)
				)
				(justify left bottom)
				(hide yes)
			)
		)
		(property "Description" ""
			(at 121.92 242.57 0)
			(effects
				(font
					(size 1.27 1.27)
				)
				(hide yes)
			)
		)
		(property "Author" "Antmicro"
			(at 130.81 250.19 0)
			(effects
				(font
					(size 1.27 1.27)
					(thickness 0.15)
				)
				(justify left bottom)
				(hide yes)
			)
		)
		(property "License" "Apache-2.0"
			(at 130.81 252.73 0)
			(effects
				(font
					(size 1.27 1.27)
					(thickness 0.15)
				)
				(justify left bottom)
				(hide yes)
			)
		)
		(pin "1"
		)
		(instances
			(project "polarfire-som"
				(path ""
					(reference "#PWR0268")
					(unit 1)
				)
			)
		)
	)
	(symbol
		(lib_id "antmicropower:+3V3")
		(at 200.66 228.6 0)
		(unit 1)
		(exclude_from_sim no)
		(in_bom yes)
		(on_board yes)
		(dnp no)
		(property "Reference" "#PWR0342"
			(at 215.9 231.14 0)
			(effects
				(font
					(size 1.27 1.27)
					(thickness 0.15)
				)
				(justify left bottom)
				(hide yes)
			)
		)
		(property "Value" "+3V3"
			(at 200.66 224.79 0)
			(effects
				(font
					(size 1.27 1.27)
					(thickness 0.15)
				)
			)
		)
		(property "Footprint" ""
			(at 215.9 236.22 0)
			(effects
				(font
					(size 1.27 1.27)
					(thickness 0.15)
				)
				(justify left bottom)
				(hide yes)
			)
		)
		(property "Datasheet" ""
			(at 215.9 238.76 0)
			(effects
				(font
					(size 1.27 1.27)
					(thickness 0.15)
				)
				(justify left bottom)
				(hide yes)
			)
		)
		(property "Description" ""
			(at 200.66 228.6 0)
			(effects
				(font
					(size 1.27 1.27)
				)
				(hide yes)
			)
		)
		(property "Author" "Antmicro"
			(at 215.9 236.22 0)
			(effects
				(font
					(size 1.27 1.27)
					(thickness 0.15)
				)
				(justify left bottom)
				(hide yes)
			)
		)
		(property "License" "Apache-2.0"
			(at 215.9 238.76 0)
			(effects
				(font
					(size 1.27 1.27)
					(thickness 0.15)
				)
				(justify left bottom)
				(hide yes)
			)
		)
		(pin "1"
		)
		(instances
			(project "polarfire-som"
				(path ""
					(reference "#PWR0342")
					(unit 1)
				)
			)
		)
	)
	(symbol
		(lib_id "antmicroCoaxialConnectorsRF:U_FL-R-SMT-1")
		(at 246.38 85.09 0)
		(unit 1)
		(exclude_from_sim no)
		(in_bom yes)
		(on_board yes)
		(dnp no)
		(fields_autoplaced yes)
		(property "Reference" "J3"
			(at 256.54 84.1697 0)
			(effects
				(font
					(size 1.27 1.27)
					(thickness 0.15)
				)
				(justify left)
			)
		)
		(property "Value" "U_FL-R-SMT-1"
			(at 266.7 92.71 0)
			(effects
				(font
					(size 1.27 1.27)
					(thickness 0.15)
				)
				(justify left bottom)
				(hide yes)
			)
		)
		(property "Footprint" "antmicro-footprints:Coax_Conn_U.FL"
			(at 266.7 95.25 0)
			(effects
				(font
					(size 1.27 1.27)
					(thickness 0.15)
				)
				(justify left bottom)
				(hide yes)
			)
		)
		(property "Datasheet" "https://media.digikey.com/pdf/Data%20Sheets/Hirose%20PDFs/UFL%20Series.pdf"
			(at 266.7 97.79 0)
			(effects
				(font
					(size 1.27 1.27)
					(thickness 0.15)
				)
				(justify left bottom)
				(hide yes)
			)
		)
		(property "Description" "U.FL (UMCC) Connector Receptacle, Male Pin 50Ohm Surface Mount Solder"
			(at 246.38 85.09 0)
			(effects
				(font
					(size 1.27 1.27)
				)
				(hide yes)
			)
		)
		(property "MPN" "U.FL-R-SMT-1(10)"
			(at 256.54 86.7097 0)
			(effects
				(font
					(size 1.27 1.27)
					(thickness 0.15)
				)
				(justify left)
			)
		)
		(property "Manufacturer" "Hirose Electric"
			(at 266.7 100.33 0)
			(effects
				(font
					(size 1.27 1.27)
					(thickness 0.15)
				)
				(justify left bottom)
				(hide yes)
			)
		)
		(property "Author" "Antmicro"
			(at 266.7 102.87 0)
			(effects
				(font
					(size 1.27 1.27)
					(thickness 0.15)
				)
				(justify left bottom)
				(hide yes)
			)
		)
		(property "License" "Apache-2.0"
			(at 266.7 105.41 0)
			(effects
				(font
					(size 1.27 1.27)
					(thickness 0.15)
				)
				(justify left bottom)
				(hide yes)
			)
		)
		(pin "1"
		)
		(pin "SH1"
		)
		(pin "SH2"
		)
		(instances
			(project "polarfire-som"
				(path ""
					(reference "J3")
					(unit 1)
				)
			)
		)
	)
	(symbol
		(lib_id "antmicroTestPoints:TP_0.75mm_SMD")
		(at 180.34 110.49 180)
		(unit 1)
		(exclude_from_sim no)
		(in_bom no)
		(on_board yes)
		(dnp no)
		(property "Reference" "TP2"
			(at 173.355 110.49 0)
			(effects
				(font
					(size 1.27 1.27)
					(thickness 0.15)
				)
			)
		)
		(property "Value" "TP_0.75mm_SMD"
			(at 169.545 106.68 0)
			(effects
				(font
					(size 1.27 1.27)
					(thickness 0.15)
				)
				(justify left bottom)
				(hide yes)
			)
		)
		(property "Footprint" "antmicro-footprints:TP_SMD_0.75mm"
			(at 169.545 104.14 0)
			(effects
				(font
					(size 1.27 1.27)
					(thickness 0.15)
				)
				(justify left bottom)
				(hide yes)
			)
		)
		(property "Datasheet" ""
			(at 162.56 97.79 0)
			(effects
				(font
					(size 1.27 1.27)
					(thickness 0.15)
				)
				(justify left bottom)
				(hide yes)
			)
		)
		(property "Description" "SMT test point"
			(at 180.34 110.49 0)
			(effects
				(font
					(size 1.27 1.27)
				)
				(hide yes)
			)
		)
		(property "MPN" ""
			(at 169.545 99.06 0)
			(effects
				(font
					(size 1.27 1.27)
					(thickness 0.15)
				)
				(justify left bottom)
				(hide yes)
			)
		)
		(property "Manufacturer" ""
			(at 169.545 104.14 0)
			(effects
				(font
					(size 1.27 1.27)
					(thickness 0.15)
				)
				(justify left bottom)
				(hide yes)
			)
		)
		(property "Author" "Antmicro"
			(at 169.545 101.6 0)
			(effects
				(font
					(size 1.27 1.27)
					(thickness 0.15)
				)
				(justify left bottom)
				(hide yes)
			)
		)
		(property "License" "Apache-2.0"
			(at 169.545 99.06 0)
			(effects
				(font
					(size 1.27 1.27)
					(thickness 0.15)
				)
				(justify left bottom)
				(hide yes)
			)
		)
		(property "Public" "False"
			(at 170.18 96.52 0)
			(effects
				(font
					(size 1.27 1.27)
				)
				(justify left bottom)
				(hide yes)
			)
		)
		(pin "1"
		)
		(instances
			(project "polarfire-som"
				(path ""
					(reference "TP2")
					(unit 1)
				)
			)
		)
	)
	(symbol
		(lib_id "antmicropower:PWR_FLAG")
		(at 157.48 92.71 90)
		(unit 1)
		(exclude_from_sim no)
		(in_bom yes)
		(on_board yes)
		(dnp no)
		(property "Reference" "#FLG023"
			(at 155.575 92.71 0)
			(effects
				(font
					(size 1.27 1.27)
				)
				(hide yes)
			)
		)
		(property "Value" "PWR_FLAG"
			(at 149.86 92.71 90)
			(effects
				(font
					(size 1.27 1.27)
				)
			)
		)
		(property "Footprint" ""
			(at 157.48 92.71 0)
			(effects
				(font
					(size 1.27 1.27)
				)
				(hide yes)
			)
		)
		(property "Datasheet" ""
			(at 157.48 92.71 0)
			(effects
				(font
					(size 1.27 1.27)
				)
				(hide yes)
			)
		)
		(property "Description" ""
			(at 157.48 92.71 0)
			(effects
				(font
					(size 1.27 1.27)
				)
				(hide yes)
			)
		)
		(pin "1"
		)
		(instances
			(project "polarfire-som"
				(path ""
					(reference "#FLG023")
					(unit 1)
				)
			)
		)
	)
	(symbol
		(lib_id "antmicropower:GND")
		(at 246.38 243.84 0)
		(unit 1)
		(exclude_from_sim no)
		(in_bom yes)
		(on_board yes)
		(dnp no)
		(fields_autoplaced yes)
		(property "Reference" "#PWR0266"
			(at 255.27 246.38 0)
			(effects
				(font
					(size 1.27 1.27)
					(thickness 0.15)
				)
				(justify left bottom)
				(hide yes)
			)
		)
		(property "Value" "GND"
			(at 246.38 248.92 0)
			(effects
				(font
					(size 1.27 1.27)
					(thickness 0.15)
				)
			)
		)
		(property "Footprint" ""
			(at 255.27 251.46 0)
			(effects
				(font
					(size 1.27 1.27)
					(thickness 0.15)
				)
				(justify left bottom)
				(hide yes)
			)
		)
		(property "Datasheet" ""
			(at 255.27 256.54 0)
			(effects
				(font
					(size 1.27 1.27)
					(thickness 0.15)
				)
				(justify left bottom)
				(hide yes)
			)
		)
		(property "Description" ""
			(at 246.38 243.84 0)
			(effects
				(font
					(size 1.27 1.27)
				)
				(hide yes)
			)
		)
		(property "Author" "Antmicro"
			(at 255.27 251.46 0)
			(effects
				(font
					(size 1.27 1.27)
					(thickness 0.15)
				)
				(justify left bottom)
				(hide yes)
			)
		)
		(property "License" "Apache-2.0"
			(at 255.27 254 0)
			(effects
				(font
					(size 1.27 1.27)
					(thickness 0.15)
				)
				(justify left bottom)
				(hide yes)
			)
		)
		(pin "1"
		)
		(instances
			(project "polarfire-som"
				(path ""
					(reference "#PWR0266")
					(unit 1)
				)
			)
		)
	)
	(symbol
		(lib_id "antmicropower:GND")
		(at 252.73 92.71 0)
		(unit 1)
		(exclude_from_sim no)
		(in_bom yes)
		(on_board yes)
		(dnp no)
		(property "Reference" "#PWR0275"
			(at 261.62 95.25 0)
			(effects
				(font
					(size 1.27 1.27)
					(thickness 0.15)
				)
				(justify left bottom)
				(hide yes)
			)
		)
		(property "Value" "GND"
			(at 252.73 96.52 0)
			(effects
				(font
					(size 1.27 1.27)
					(thickness 0.15)
				)
			)
		)
		(property "Footprint" ""
			(at 261.62 100.33 0)
			(effects
				(font
					(size 1.27 1.27)
					(thickness 0.15)
				)
				(justify left bottom)
				(hide yes)
			)
		)
		(property "Datasheet" ""
			(at 261.62 105.41 0)
			(effects
				(font
					(size 1.27 1.27)
					(thickness 0.15)
				)
				(justify left bottom)
				(hide yes)
			)
		)
		(property "Description" ""
			(at 252.73 92.71 0)
			(effects
				(font
					(size 1.27 1.27)
				)
				(hide yes)
			)
		)
		(property "Author" "Antmicro"
			(at 261.62 100.33 0)
			(effects
				(font
					(size 1.27 1.27)
					(thickness 0.15)
				)
				(justify left bottom)
				(hide yes)
			)
		)
		(property "License" "Apache-2.0"
			(at 261.62 102.87 0)
			(effects
				(font
					(size 1.27 1.27)
					(thickness 0.15)
				)
				(justify left bottom)
				(hide yes)
			)
		)
		(pin "1"
		)
		(instances
			(project "polarfire-som"
				(path ""
					(reference "#PWR0275")
					(unit 1)
				)
			)
		)
	)
	(symbol
		(lib_id "antmicropower:+3V3")
		(at 177.8 228.6 0)
		(unit 1)
		(exclude_from_sim no)
		(in_bom yes)
		(on_board yes)
		(dnp no)
		(property "Reference" "#PWR0265"
			(at 193.04 231.14 0)
			(effects
				(font
					(size 1.27 1.27)
					(thickness 0.15)
				)
				(justify left bottom)
				(hide yes)
			)
		)
		(property "Value" "+3V3"
			(at 177.8 224.79 0)
			(effects
				(font
					(size 1.27 1.27)
					(thickness 0.15)
				)
			)
		)
		(property "Footprint" ""
			(at 193.04 236.22 0)
			(effects
				(font
					(size 1.27 1.27)
					(thickness 0.15)
				)
				(justify left bottom)
				(hide yes)
			)
		)
		(property "Datasheet" ""
			(at 193.04 238.76 0)
			(effects
				(font
					(size 1.27 1.27)
					(thickness 0.15)
				)
				(justify left bottom)
				(hide yes)
			)
		)
		(property "Description" ""
			(at 177.8 228.6 0)
			(effects
				(font
					(size 1.27 1.27)
				)
				(hide yes)
			)
		)
		(property "Author" "Antmicro"
			(at 193.04 236.22 0)
			(effects
				(font
					(size 1.27 1.27)
					(thickness 0.15)
				)
				(justify left bottom)
				(hide yes)
			)
		)
		(property "License" "Apache-2.0"
			(at 193.04 238.76 0)
			(effects
				(font
					(size 1.27 1.27)
					(thickness 0.15)
				)
				(justify left bottom)
				(hide yes)
			)
		)
		(pin "1"
		)
		(instances
			(project "polarfire-som"
				(path ""
					(reference "#PWR0265")
					(unit 1)
				)
			)
		)
	)
	(symbol
		(lib_id "antmicroResistors0402:R_10k_0402")
		(at 121.92 231.14 90)
		(unit 1)
		(exclude_from_sim no)
		(in_bom yes)
		(on_board yes)
		(dnp no)
		(property "Reference" "R144"
			(at 123.19 227.33 90)
			(effects
				(font
					(size 1.27 1.27)
					(thickness 0.15)
				)
				(justify right)
			)
		)
		(property "Value" "R_10k_0402"
			(at 134.62 210.82 0)
			(effects
				(font
					(size 1.27 1.27)
					(thickness 0.15)
				)
				(justify left bottom)
				(hide yes)
			)
		)
		(property "Footprint" "antmicro-footprints:R_0402_1005Metric"
			(at 137.16 210.82 0)
			(effects
				(font
					(size 1.27 1.27)
					(thickness 0.15)
				)
				(justify left bottom)
				(hide yes)
			)
		)
		(property "Datasheet" "https://www.bourns.com/docs/product-datasheets/cr.pdf"
			(at 139.7 210.82 0)
			(effects
				(font
					(size 1.27 1.27)
					(thickness 0.15)
				)
				(justify left bottom)
				(hide yes)
			)
		)
		(property "Description" "SMD Chip Resistor, 10 kohm, ± 1%, 62.5 mW, 0402 [1005 Metric], Thick Film, General Purpose"
			(at 121.92 231.14 0)
			(effects
				(font
					(size 1.27 1.27)
				)
				(hide yes)
			)
		)
		(property "MPN" "CR0402-FX-1002GLF"
			(at 142.24 210.82 0)
			(effects
				(font
					(size 1.27 1.27)
					(thickness 0.15)
				)
				(justify left bottom)
				(hide yes)
			)
		)
		(property "Manufacturer" "Bourns"
			(at 144.78 210.82 0)
			(effects
				(font
					(size 1.27 1.27)
					(thickness 0.15)
				)
				(justify left bottom)
				(hide yes)
			)
		)
		(property "License" "Apache-2.0"
			(at 147.32 210.82 0)
			(effects
				(font
					(size 1.27 1.27)
					(thickness 0.15)
				)
				(justify left bottom)
				(hide yes)
			)
		)
		(property "Author" "Antmicro"
			(at 149.86 210.82 0)
			(effects
				(font
					(size 1.27 1.27)
					(thickness 0.15)
				)
				(justify left bottom)
				(hide yes)
			)
		)
		(property "Val" "10k"
			(at 123.19 229.87 90)
			(effects
				(font
					(size 1.27 1.27)
					(thickness 0.15)
				)
				(justify right)
			)
		)
		(property "Tolerance" "1%"
			(at 132.08 210.82 0)
			(effects
				(font
					(size 1.27 1.27)
				)
				(justify left bottom)
				(hide yes)
			)
		)
		(property "Public" ""
			(at 152.4 210.82 0)
			(effects
				(font
					(size 1.27 1.27)
				)
				(justify left bottom)
				(hide yes)
			)
		)
		(pin "1"
		)
		(pin "2"
		)
		(instances
			(project "polarfire-som"
				(path ""
					(reference "R144")
					(unit 1)
				)
			)
		)
	)
	(symbol
		(lib_id "antmicroOscillators:Oscillator_32.768kHz_ECS_2520MV")
		(at 48.26 233.68 0)
		(unit 1)
		(exclude_from_sim no)
		(in_bom yes)
		(on_board yes)
		(dnp no)
		(fields_autoplaced yes)
		(property "Reference" "Y4"
			(at 57.785 223.52 0)
			(effects
				(font
					(size 1.27 1.27)
					(thickness 0.15)
				)
			)
		)
		(property "Value" "Oscillator_32.768kHz_ECS_2520MV"
			(at 74.295 246.38 0)
			(effects
				(font
					(size 1.27 1.27)
					(thickness 0.15)
				)
				(justify left bottom)
				(hide yes)
			)
		)
		(property "Footprint" "antmicro-footprints:Oscillator_SMD_ECS_2520MV_2.5x2mm"
			(at 74.295 248.92 0)
			(effects
				(font
					(size 1.27 1.27)
					(thickness 0.15)
				)
				(justify left bottom)
				(hide yes)
			)
		)
		(property "Datasheet" "https://ecsxtal.com/store/pdf/ECS-327MVATX.pdf"
			(at 74.295 251.46 0)
			(effects
				(font
					(size 1.27 1.27)
					(thickness 0.15)
				)
				(justify left bottom)
				(hide yes)
			)
		)
		(property "Description" "32.768 kHz XO (Standard) CMOS Oscillator 1.6V ~ 3.6V Enable/Disable 4-SMD, No Lead"
			(at 48.26 233.68 0)
			(effects
				(font
					(size 1.27 1.27)
				)
				(hide yes)
			)
		)
		(property "Manufacturer" "ECS Inc. International"
			(at 74.295 241.3 0)
			(effects
				(font
					(size 1.27 1.27)
					(thickness 0.15)
				)
				(justify left bottom)
				(hide yes)
			)
		)
		(property "MPN" "ECS-327MVATX-2-CN-TR3"
			(at 57.785 226.06 0)
			(effects
				(font
					(size 1.27 1.27)
					(thickness 0.15)
				)
			)
		)
		(property "Val" "32.768 kHz"
			(at 57.785 228.6 0)
			(effects
				(font
					(size 1.27 1.27)
					(thickness 0.15)
				)
			)
		)
		(property "Author" "Antmicro"
			(at 74.295 254 0)
			(effects
				(font
					(size 1.27 1.27)
					(thickness 0.15)
				)
				(justify left bottom)
				(hide yes)
			)
		)
		(property "License" "Apache-2.0"
			(at 74.295 256.54 0)
			(effects
				(font
					(size 1.27 1.27)
					(thickness 0.15)
				)
				(justify left bottom)
				(hide yes)
			)
		)
		(property "Public" ""
			(at 80.01 257.81 0)
			(effects
				(font
					(size 1.27 1.27)
				)
				(justify left bottom)
				(hide yes)
			)
		)
		(pin "1"
		)
		(pin "2"
		)
		(pin "3"
		)
		(pin "4"
		)
		(instances
			(project "polarfire-som"
				(path ""
					(reference "Y4")
					(unit 1)
				)
			)
		)
	)
	(symbol
		(lib_id "antmicroResistors0402:R_10k_0402")
		(at 265.43 241.3 90)
		(unit 1)
		(exclude_from_sim no)
		(in_bom yes)
		(on_board yes)
		(dnp no)
		(property "Reference" "R149"
			(at 266.7 237.49 90)
			(effects
				(font
					(size 1.27 1.27)
					(thickness 0.15)
				)
				(justify right)
			)
		)
		(property "Value" "R_10k_0402"
			(at 278.13 220.98 0)
			(effects
				(font
					(size 1.27 1.27)
					(thickness 0.15)
				)
				(justify left bottom)
				(hide yes)
			)
		)
		(property "Footprint" "antmicro-footprints:R_0402_1005Metric"
			(at 280.67 220.98 0)
			(effects
				(font
					(size 1.27 1.27)
					(thickness 0.15)
				)
				(justify left bottom)
				(hide yes)
			)
		)
		(property "Datasheet" "https://www.bourns.com/docs/product-datasheets/cr.pdf"
			(at 283.21 220.98 0)
			(effects
				(font
					(size 1.27 1.27)
					(thickness 0.15)
				)
				(justify left bottom)
				(hide yes)
			)
		)
		(property "Description" "SMD Chip Resistor, 10 kohm, ± 1%, 62.5 mW, 0402 [1005 Metric], Thick Film, General Purpose"
			(at 265.43 241.3 0)
			(effects
				(font
					(size 1.27 1.27)
				)
				(hide yes)
			)
		)
		(property "MPN" "CR0402-FX-1002GLF"
			(at 285.75 220.98 0)
			(effects
				(font
					(size 1.27 1.27)
					(thickness 0.15)
				)
				(justify left bottom)
				(hide yes)
			)
		)
		(property "Manufacturer" "Bourns"
			(at 288.29 220.98 0)
			(effects
				(font
					(size 1.27 1.27)
					(thickness 0.15)
				)
				(justify left bottom)
				(hide yes)
			)
		)
		(property "License" "Apache-2.0"
			(at 290.83 220.98 0)
			(effects
				(font
					(size 1.27 1.27)
					(thickness 0.15)
				)
				(justify left bottom)
				(hide yes)
			)
		)
		(property "Author" "Antmicro"
			(at 293.37 220.98 0)
			(effects
				(font
					(size 1.27 1.27)
					(thickness 0.15)
				)
				(justify left bottom)
				(hide yes)
			)
		)
		(property "Val" "10k"
			(at 266.7 240.03 90)
			(effects
				(font
					(size 1.27 1.27)
					(thickness 0.15)
				)
				(justify right)
			)
		)
		(property "Tolerance" "1%"
			(at 275.59 220.98 0)
			(effects
				(font
					(size 1.27 1.27)
				)
				(justify left bottom)
				(hide yes)
			)
		)
		(property "Public" ""
			(at 295.91 220.98 0)
			(effects
				(font
					(size 1.27 1.27)
				)
				(justify left bottom)
				(hide yes)
			)
		)
		(pin "1"
		)
		(pin "2"
		)
		(instances
			(project "polarfire-som"
				(path ""
					(reference "R149")
					(unit 1)
				)
			)
		)
	)
	(symbol
		(lib_id "antmicroCapacitors0402:C_100n_0402")
		(at 186.69 236.22 90)
		(unit 1)
		(exclude_from_sim no)
		(in_bom yes)
		(on_board yes)
		(dnp no)
		(property "Reference" "C230"
			(at 187.96 232.41 90)
			(effects
				(font
					(size 1.27 1.27)
					(thickness 0.15)
				)
				(justify right)
			)
		)
		(property "Value" "C_100n_0402"
			(at 196.85 215.9 0)
			(effects
				(font
					(size 1.27 1.27)
					(thickness 0.15)
				)
				(justify left bottom)
				(hide yes)
			)
		)
		(property "Footprint" "antmicro-footprints:C_0402_1005Metric"
			(at 199.39 215.9 0)
			(effects
				(font
					(size 1.27 1.27)
					(thickness 0.15)
				)
				(justify left bottom)
				(hide yes)
			)
		)
		(property "Datasheet" "https://www.murata.com/products/productdetail?partno=GRM155R61H104KE14%23"
			(at 201.93 215.9 0)
			(effects
				(font
					(size 1.27 1.27)
					(thickness 0.15)
				)
				(justify left bottom)
				(hide yes)
			)
		)
		(property "Description" "SMD Multilayer Ceramic Capacitor, 0.1 µF, 50 V, 0402 [1005 Metric], ± 10%, X5R, GRM Series"
			(at 186.69 236.22 0)
			(effects
				(font
					(size 1.27 1.27)
				)
				(hide yes)
			)
		)
		(property "MPN" "GRM155R61H104KE14D"
			(at 204.47 215.9 0)
			(effects
				(font
					(size 1.27 1.27)
					(thickness 0.15)
				)
				(justify left bottom)
				(hide yes)
			)
		)
		(property "Manufacturer" "Murata"
			(at 207.01 215.9 0)
			(effects
				(font
					(size 1.27 1.27)
					(thickness 0.15)
				)
				(justify left bottom)
				(hide yes)
			)
		)
		(property "License" "Apache-2.0"
			(at 209.55 215.9 0)
			(effects
				(font
					(size 1.27 1.27)
					(thickness 0.15)
				)
				(justify left bottom)
				(hide yes)
			)
		)
		(property "Author" "Antmicro"
			(at 212.09 215.9 0)
			(effects
				(font
					(size 1.27 1.27)
					(thickness 0.15)
				)
				(justify left bottom)
				(hide yes)
			)
		)
		(property "Val" "100n"
			(at 193.04 234.95 90)
			(effects
				(font
					(size 1.27 1.27)
					(thickness 0.15)
				)
				(justify left bottom)
			)
		)
		(property "Voltage" "50V"
			(at 214.63 215.9 0)
			(effects
				(font
					(size 1.27 1.27)
				)
				(justify left bottom)
				(hide yes)
			)
		)
		(property "Dielectric" "X5R"
			(at 217.17 215.9 0)
			(effects
				(font
					(size 1.27 1.27)
				)
				(justify left bottom)
				(hide yes)
			)
		)
		(property "Public" ""
			(at 219.71 215.9 0)
			(effects
				(font
					(size 1.27 1.27)
				)
				(justify left bottom)
				(hide yes)
			)
		)
		(pin "1"
		)
		(pin "2"
		)
		(instances
			(project "polarfire-som"
				(path ""
					(reference "C230")
					(unit 1)
				)
			)
		)
	)
	(symbol
		(lib_id "antmicropower:+3V3")
		(at 130.81 224.79 0)
		(unit 1)
		(exclude_from_sim no)
		(in_bom yes)
		(on_board yes)
		(dnp no)
		(property "Reference" "#PWR0341"
			(at 146.05 227.33 0)
			(effects
				(font
					(size 1.27 1.27)
					(thickness 0.15)
				)
				(justify left bottom)
				(hide yes)
			)
		)
		(property "Value" "+3V3"
			(at 130.81 220.98 0)
			(effects
				(font
					(size 1.27 1.27)
					(thickness 0.15)
				)
			)
		)
		(property "Footprint" ""
			(at 146.05 232.41 0)
			(effects
				(font
					(size 1.27 1.27)
					(thickness 0.15)
				)
				(justify left bottom)
				(hide yes)
			)
		)
		(property "Datasheet" ""
			(at 146.05 234.95 0)
			(effects
				(font
					(size 1.27 1.27)
					(thickness 0.15)
				)
				(justify left bottom)
				(hide yes)
			)
		)
		(property "Description" ""
			(at 130.81 224.79 0)
			(effects
				(font
					(size 1.27 1.27)
				)
				(hide yes)
			)
		)
		(property "Author" "Antmicro"
			(at 146.05 232.41 0)
			(effects
				(font
					(size 1.27 1.27)
					(thickness 0.15)
				)
				(justify left bottom)
				(hide yes)
			)
		)
		(property "License" "Apache-2.0"
			(at 146.05 234.95 0)
			(effects
				(font
					(size 1.27 1.27)
					(thickness 0.15)
				)
				(justify left bottom)
				(hide yes)
			)
		)
		(pin "1"
		)
		(instances
			(project "polarfire-som"
				(path ""
					(reference "#PWR0341")
					(unit 1)
				)
			)
		)
	)
	(symbol
		(lib_id "antmicroTestPoints:TP_0.75mm_SMD")
		(at 180.34 113.03 180)
		(unit 1)
		(exclude_from_sim no)
		(in_bom no)
		(on_board yes)
		(dnp no)
		(property "Reference" "TP3"
			(at 173.355 113.03 0)
			(effects
				(font
					(size 1.27 1.27)
					(thickness 0.15)
				)
			)
		)
		(property "Value" "TP_0.75mm_SMD"
			(at 169.545 109.22 0)
			(effects
				(font
					(size 1.27 1.27)
					(thickness 0.15)
				)
				(justify left bottom)
				(hide yes)
			)
		)
		(property "Footprint" "antmicro-footprints:TP_SMD_0.75mm"
			(at 169.545 106.68 0)
			(effects
				(font
					(size 1.27 1.27)
					(thickness 0.15)
				)
				(justify left bottom)
				(hide yes)
			)
		)
		(property "Datasheet" ""
			(at 162.56 100.33 0)
			(effects
				(font
					(size 1.27 1.27)
					(thickness 0.15)
				)
				(justify left bottom)
				(hide yes)
			)
		)
		(property "Description" "SMT test point"
			(at 180.34 113.03 0)
			(effects
				(font
					(size 1.27 1.27)
				)
				(hide yes)
			)
		)
		(property "MPN" ""
			(at 169.545 101.6 0)
			(effects
				(font
					(size 1.27 1.27)
					(thickness 0.15)
				)
				(justify left bottom)
				(hide yes)
			)
		)
		(property "Manufacturer" ""
			(at 169.545 106.68 0)
			(effects
				(font
					(size 1.27 1.27)
					(thickness 0.15)
				)
				(justify left bottom)
				(hide yes)
			)
		)
		(property "Author" "Antmicro"
			(at 169.545 104.14 0)
			(effects
				(font
					(size 1.27 1.27)
					(thickness 0.15)
				)
				(justify left bottom)
				(hide yes)
			)
		)
		(property "License" "Apache-2.0"
			(at 169.545 101.6 0)
			(effects
				(font
					(size 1.27 1.27)
					(thickness 0.15)
				)
				(justify left bottom)
				(hide yes)
			)
		)
		(property "Public" "False"
			(at 170.18 99.06 0)
			(effects
				(font
					(size 1.27 1.27)
				)
				(justify left bottom)
				(hide yes)
			)
		)
		(pin "1"
		)
		(instances
			(project "polarfire-som"
				(path ""
					(reference "TP3")
					(unit 1)
				)
			)
		)
	)
	(symbol
		(lib_id "antmicroRFTransceiverModules:WiFi_Bluetooth_LBEE5PK2AE")
		(at 187.96 85.09 0)
		(unit 1)
		(exclude_from_sim no)
		(in_bom yes)
		(on_board yes)
		(dnp no)
		(fields_autoplaced yes)
		(property "Reference" "U26"
			(at 207.01 77.47 0)
			(effects
				(font
					(size 1.27 1.27)
					(thickness 0.15)
				)
			)
		)
		(property "Value" "WiFi_Bluetooth_LBEE5PK2AE"
			(at 243.84 92.71 0)
			(effects
				(font
					(size 1.27 1.27)
					(thickness 0.15)
				)
				(justify left bottom)
				(hide yes)
			)
		)
		(property "Footprint" "antmicro-footprints:WiFi_Bluetooth_Module_LBEE5PK2AE"
			(at 243.84 95.25 0)
			(effects
				(font
					(size 1.27 1.27)
					(thickness 0.15)
				)
				(justify left bottom)
				(hide yes)
			)
		)
		(property "Datasheet" "https://www.murata.com/products/productdata/8816428220446/type2ae.pdf"
			(at 243.84 97.79 0)
			(effects
				(font
					(size 1.27 1.27)
					(thickness 0.15)
				)
				(justify left bottom)
				(hide yes)
			)
		)
		(property "Description" "WiFi and Bluetooth Module"
			(at 187.96 85.09 0)
			(effects
				(font
					(size 1.27 1.27)
				)
				(hide yes)
			)
		)
		(property "Manufacturer" "Murata"
			(at 243.84 100.33 0)
			(effects
				(font
					(size 1.27 1.27)
					(thickness 0.15)
				)
				(justify left bottom)
				(hide yes)
			)
		)
		(property "MPN" "LBEE5PK2AE"
			(at 207.01 80.01 0)
			(effects
				(font
					(size 1.27 1.27)
					(thickness 0.15)
				)
			)
		)
		(property "Author" "Antmicro"
			(at 243.84 102.87 0)
			(effects
				(font
					(size 1.27 1.27)
					(thickness 0.15)
				)
				(justify left bottom)
				(hide yes)
			)
		)
		(property "License" "Apache-2.0"
			(at 243.84 105.41 0)
			(effects
				(font
					(size 1.27 1.27)
					(thickness 0.15)
				)
				(justify left bottom)
				(hide yes)
			)
		)
		(pin "1"
		)
		(pin "10"
		)
		(pin "11"
		)
		(pin "12"
		)
		(pin "13"
		)
		(pin "14"
		)
		(pin "15"
		)
		(pin "16"
		)
		(pin "17"
		)
		(pin "18"
		)
		(pin "19"
		)
		(pin "2"
		)
		(pin "20"
		)
		(pin "21"
		)
		(pin "22"
		)
		(pin "23"
		)
		(pin "24"
		)
		(pin "25"
		)
		(pin "26"
		)
		(pin "27"
		)
		(pin "28"
		)
		(pin "29"
		)
		(pin "3"
		)
		(pin "30"
		)
		(pin "31"
		)
		(pin "32"
		)
		(pin "33"
		)
		(pin "34"
		)
		(pin "35"
		)
		(pin "36"
		)
		(pin "37"
		)
		(pin "38"
		)
		(pin "39"
		)
		(pin "4"
		)
		(pin "40"
		)
		(pin "41"
		)
		(pin "42"
		)
		(pin "43"
		)
		(pin "44"
		)
		(pin "45"
		)
		(pin "46"
		)
		(pin "47"
		)
		(pin "48"
		)
		(pin "49"
		)
		(pin "5"
		)
		(pin "50"
		)
		(pin "51"
		)
		(pin "52"
		)
		(pin "53"
		)
		(pin "54"
		)
		(pin "55"
		)
		(pin "56"
		)
		(pin "57"
		)
		(pin "58"
		)
		(pin "59"
		)
		(pin "6"
		)
		(pin "60"
		)
		(pin "61"
		)
		(pin "62"
		)
		(pin "63"
		)
		(pin "64"
		)
		(pin "65"
		)
		(pin "66"
		)
		(pin "67"
		)
		(pin "68"
		)
		(pin "69"
		)
		(pin "7"
		)
		(pin "70"
		)
		(pin "71"
		)
		(pin "72"
		)
		(pin "73"
		)
		(pin "74"
		)
		(pin "75"
		)
		(pin "76"
		)
		(pin "77"
		)
		(pin "8"
		)
		(pin "9"
		)
		(instances
			(project "polarfire-som"
				(path ""
					(reference "U26")
					(unit 1)
				)
			)
		)
	)
	(symbol
		(lib_id "antmicroTestPoints:TP_0.75mm_SMD")
		(at 180.34 130.81 180)
		(unit 1)
		(exclude_from_sim no)
		(in_bom no)
		(on_board yes)
		(dnp no)
		(property "Reference" "TP8"
			(at 173.355 130.81 0)
			(effects
				(font
					(size 1.27 1.27)
					(thickness 0.15)
				)
			)
		)
		(property "Value" "TP_0.75mm_SMD"
			(at 169.545 127 0)
			(effects
				(font
					(size 1.27 1.27)
					(thickness 0.15)
				)
				(justify left bottom)
				(hide yes)
			)
		)
		(property "Footprint" "antmicro-footprints:TP_SMD_0.75mm"
			(at 169.545 124.46 0)
			(effects
				(font
					(size 1.27 1.27)
					(thickness 0.15)
				)
				(justify left bottom)
				(hide yes)
			)
		)
		(property "Datasheet" ""
			(at 162.56 118.11 0)
			(effects
				(font
					(size 1.27 1.27)
					(thickness 0.15)
				)
				(justify left bottom)
				(hide yes)
			)
		)
		(property "Description" "SMT test point"
			(at 180.34 130.81 0)
			(effects
				(font
					(size 1.27 1.27)
				)
				(hide yes)
			)
		)
		(property "MPN" ""
			(at 169.545 119.38 0)
			(effects
				(font
					(size 1.27 1.27)
					(thickness 0.15)
				)
				(justify left bottom)
				(hide yes)
			)
		)
		(property "Manufacturer" ""
			(at 169.545 124.46 0)
			(effects
				(font
					(size 1.27 1.27)
					(thickness 0.15)
				)
				(justify left bottom)
				(hide yes)
			)
		)
		(property "Author" "Antmicro"
			(at 169.545 121.92 0)
			(effects
				(font
					(size 1.27 1.27)
					(thickness 0.15)
				)
				(justify left bottom)
				(hide yes)
			)
		)
		(property "License" "Apache-2.0"
			(at 169.545 119.38 0)
			(effects
				(font
					(size 1.27 1.27)
					(thickness 0.15)
				)
				(justify left bottom)
				(hide yes)
			)
		)
		(property "Public" "False"
			(at 170.18 116.84 0)
			(effects
				(font
					(size 1.27 1.27)
				)
				(justify left bottom)
				(hide yes)
			)
		)
		(pin "1"
		)
		(instances
			(project "polarfire-som"
				(path ""
					(reference "TP8")
					(unit 1)
				)
			)
		)
	)
	(symbol
		(lib_id "antmicroTestPoints:TP_0.75mm_SMD")
		(at 233.68 121.92 0)
		(unit 1)
		(exclude_from_sim no)
		(in_bom no)
		(on_board yes)
		(dnp no)
		(property "Reference" "TP31"
			(at 240.665 121.92 0)
			(effects
				(font
					(size 1.27 1.27)
					(thickness 0.15)
				)
			)
		)
		(property "Value" "TP_0.75mm_SMD"
			(at 244.475 125.73 0)
			(effects
				(font
					(size 1.27 1.27)
					(thickness 0.15)
				)
				(justify left bottom)
				(hide yes)
			)
		)
		(property "Footprint" "antmicro-footprints:TP_SMD_0.75mm"
			(at 244.475 128.27 0)
			(effects
				(font
					(size 1.27 1.27)
					(thickness 0.15)
				)
				(justify left bottom)
				(hide yes)
			)
		)
		(property "Datasheet" ""
			(at 251.46 134.62 0)
			(effects
				(font
					(size 1.27 1.27)
					(thickness 0.15)
				)
				(justify left bottom)
				(hide yes)
			)
		)
		(property "Description" "SMT test point"
			(at 233.68 121.92 0)
			(effects
				(font
					(size 1.27 1.27)
				)
				(hide yes)
			)
		)
		(property "MPN" ""
			(at 244.475 133.35 0)
			(effects
				(font
					(size 1.27 1.27)
					(thickness 0.15)
				)
				(justify left bottom)
				(hide yes)
			)
		)
		(property "Manufacturer" ""
			(at 244.475 128.27 0)
			(effects
				(font
					(size 1.27 1.27)
					(thickness 0.15)
				)
				(justify left bottom)
				(hide yes)
			)
		)
		(property "Author" "Antmicro"
			(at 244.475 130.81 0)
			(effects
				(font
					(size 1.27 1.27)
					(thickness 0.15)
				)
				(justify left bottom)
				(hide yes)
			)
		)
		(property "License" "Apache-2.0"
			(at 244.475 133.35 0)
			(effects
				(font
					(size 1.27 1.27)
					(thickness 0.15)
				)
				(justify left bottom)
				(hide yes)
			)
		)
		(property "Public" "False"
			(at 243.84 135.89 0)
			(effects
				(font
					(size 1.27 1.27)
				)
				(justify left bottom)
				(hide yes)
			)
		)
		(pin "1"
		)
		(instances
			(project "polarfire-som"
				(path ""
					(reference "TP31")
					(unit 1)
				)
			)
		)
	)
	(symbol
		(lib_id "antmicroCapacitors0402:C_10u_0402")
		(at 200.66 236.22 90)
		(unit 1)
		(exclude_from_sim no)
		(in_bom yes)
		(on_board yes)
		(dnp no)
		(property "Reference" "C287"
			(at 201.93 232.41 90)
			(effects
				(font
					(size 1.27 1.27)
					(thickness 0.15)
				)
				(justify right)
			)
		)
		(property "Value" "C_10u_0402"
			(at 210.82 215.9 0)
			(effects
				(font
					(size 1.27 1.27)
					(thickness 0.15)
				)
				(justify left bottom)
				(hide yes)
			)
		)
		(property "Footprint" "antmicro-footprints:C_0402_1005Metric"
			(at 213.36 215.9 0)
			(effects
				(font
					(size 1.27 1.27)
					(thickness 0.15)
				)
				(justify left bottom)
				(hide yes)
			)
		)
		(property "Datasheet" "https://www.yageo.com/en/Chart/Download/pdf/CC0402MRX5R5BB106"
			(at 215.9 215.9 0)
			(effects
				(font
					(size 1.27 1.27)
					(thickness 0.15)
				)
				(justify left bottom)
				(hide yes)
			)
		)
		(property "Description" "SMD Multilayer Ceramic Capacitor, 10 µF, 6.3 V, 0402 [1005 Metric], ± 20%, X5R, CC Series"
			(at 200.66 236.22 0)
			(effects
				(font
					(size 1.27 1.27)
				)
				(hide yes)
			)
		)
		(property "MPN" "CC0402MRX5R5BB106"
			(at 218.44 215.9 0)
			(effects
				(font
					(size 1.27 1.27)
					(thickness 0.15)
				)
				(justify left bottom)
				(hide yes)
			)
		)
		(property "Manufacturer" "YAGEO"
			(at 220.98 215.9 0)
			(effects
				(font
					(size 1.27 1.27)
					(thickness 0.15)
				)
				(justify left bottom)
				(hide yes)
			)
		)
		(property "License" "Apache-2.0"
			(at 223.52 215.9 0)
			(effects
				(font
					(size 1.27 1.27)
					(thickness 0.15)
				)
				(justify left bottom)
				(hide yes)
			)
		)
		(property "Author" "Antmicro"
			(at 226.06 215.9 0)
			(effects
				(font
					(size 1.27 1.27)
					(thickness 0.15)
				)
				(justify left bottom)
				(hide yes)
			)
		)
		(property "Val" "10u"
			(at 205.74 234.95 90)
			(effects
				(font
					(size 1.27 1.27)
					(thickness 0.15)
				)
				(justify left bottom)
			)
		)
		(property "Voltage" ""
			(at 228.6 215.9 0)
			(effects
				(font
					(size 1.27 1.27)
				)
				(justify left bottom)
				(hide yes)
			)
		)
		(property "Dielectric" ""
			(at 231.14 215.9 0)
			(effects
				(font
					(size 1.27 1.27)
				)
				(justify left bottom)
				(hide yes)
			)
		)
		(property "Public" ""
			(at 233.68 215.9 0)
			(effects
				(font
					(size 1.27 1.27)
				)
				(justify left bottom)
				(hide yes)
			)
		)
		(pin "1"
		)
		(pin "2"
		)
		(instances
			(project "polarfire-som"
				(path ""
					(reference "C287")
					(unit 1)
				)
			)
		)
	)
	(symbol
		(lib_id "antmicroResistors0402:R_10k_0402")
		(at 250.19 241.3 90)
		(unit 1)
		(exclude_from_sim no)
		(in_bom yes)
		(on_board yes)
		(dnp no)
		(property "Reference" "R143"
			(at 251.46 237.49 90)
			(effects
				(font
					(size 1.27 1.27)
					(thickness 0.15)
				)
				(justify right)
			)
		)
		(property "Value" "R_10k_0402"
			(at 262.89 220.98 0)
			(effects
				(font
					(size 1.27 1.27)
					(thickness 0.15)
				)
				(justify left bottom)
				(hide yes)
			)
		)
		(property "Footprint" "antmicro-footprints:R_0402_1005Metric"
			(at 265.43 220.98 0)
			(effects
				(font
					(size 1.27 1.27)
					(thickness 0.15)
				)
				(justify left bottom)
				(hide yes)
			)
		)
		(property "Datasheet" "https://www.bourns.com/docs/product-datasheets/cr.pdf"
			(at 267.97 220.98 0)
			(effects
				(font
					(size 1.27 1.27)
					(thickness 0.15)
				)
				(justify left bottom)
				(hide yes)
			)
		)
		(property "Description" "SMD Chip Resistor, 10 kohm, ± 1%, 62.5 mW, 0402 [1005 Metric], Thick Film, General Purpose"
			(at 250.19 241.3 0)
			(effects
				(font
					(size 1.27 1.27)
				)
				(hide yes)
			)
		)
		(property "MPN" "CR0402-FX-1002GLF"
			(at 270.51 220.98 0)
			(effects
				(font
					(size 1.27 1.27)
					(thickness 0.15)
				)
				(justify left bottom)
				(hide yes)
			)
		)
		(property "Manufacturer" "Bourns"
			(at 273.05 220.98 0)
			(effects
				(font
					(size 1.27 1.27)
					(thickness 0.15)
				)
				(justify left bottom)
				(hide yes)
			)
		)
		(property "License" "Apache-2.0"
			(at 275.59 220.98 0)
			(effects
				(font
					(size 1.27 1.27)
					(thickness 0.15)
				)
				(justify left bottom)
				(hide yes)
			)
		)
		(property "Author" "Antmicro"
			(at 278.13 220.98 0)
			(effects
				(font
					(size 1.27 1.27)
					(thickness 0.15)
				)
				(justify left bottom)
				(hide yes)
			)
		)
		(property "Val" "10k"
			(at 251.46 240.03 90)
			(effects
				(font
					(size 1.27 1.27)
					(thickness 0.15)
				)
				(justify right)
			)
		)
		(property "Tolerance" "1%"
			(at 260.35 220.98 0)
			(effects
				(font
					(size 1.27 1.27)
				)
				(justify left bottom)
				(hide yes)
			)
		)
		(property "Public" ""
			(at 280.67 220.98 0)
			(effects
				(font
					(size 1.27 1.27)
				)
				(justify left bottom)
				(hide yes)
			)
		)
		(pin "1"
		)
		(pin "2"
		)
		(instances
			(project "polarfire-som"
				(path ""
					(reference "R143")
					(unit 1)
				)
			)
		)
	)
	(symbol
		(lib_id "antmicropower:GND")
		(at 35.56 241.3 0)
		(unit 1)
		(exclude_from_sim no)
		(in_bom yes)
		(on_board yes)
		(dnp no)
		(property "Reference" "#PWR0264"
			(at 44.45 243.84 0)
			(effects
				(font
					(size 1.27 1.27)
					(thickness 0.15)
				)
				(justify left bottom)
				(hide yes)
			)
		)
		(property "Value" "GND"
			(at 35.56 245.11 0)
			(effects
				(font
					(size 1.27 1.27)
					(thickness 0.15)
				)
			)
		)
		(property "Footprint" ""
			(at 44.45 248.92 0)
			(effects
				(font
					(size 1.27 1.27)
					(thickness 0.15)
				)
				(justify left bottom)
				(hide yes)
			)
		)
		(property "Datasheet" ""
			(at 44.45 254 0)
			(effects
				(font
					(size 1.27 1.27)
					(thickness 0.15)
				)
				(justify left bottom)
				(hide yes)
			)
		)
		(property "Description" ""
			(at 35.56 241.3 0)
			(effects
				(font
					(size 1.27 1.27)
				)
				(hide yes)
			)
		)
		(property "Author" "Antmicro"
			(at 44.45 248.92 0)
			(effects
				(font
					(size 1.27 1.27)
					(thickness 0.15)
				)
				(justify left bottom)
				(hide yes)
			)
		)
		(property "License" "Apache-2.0"
			(at 44.45 251.46 0)
			(effects
				(font
					(size 1.27 1.27)
					(thickness 0.15)
				)
				(justify left bottom)
				(hide yes)
			)
		)
		(pin "1"
		)
		(instances
			(project "polarfire-som"
				(path ""
					(reference "#PWR0264")
					(unit 1)
				)
			)
		)
	)
	(symbol
		(lib_id "antmicropower:GND")
		(at 246.38 139.7 0)
		(unit 1)
		(exclude_from_sim no)
		(in_bom yes)
		(on_board yes)
		(dnp no)
		(property "Reference" "#PWR0274"
			(at 255.27 142.24 0)
			(effects
				(font
					(size 1.27 1.27)
					(thickness 0.15)
				)
				(justify left bottom)
				(hide yes)
			)
		)
		(property "Value" "GND"
			(at 246.38 143.51 0)
			(effects
				(font
					(size 1.27 1.27)
					(thickness 0.15)
				)
			)
		)
		(property "Footprint" ""
			(at 255.27 147.32 0)
			(effects
				(font
					(size 1.27 1.27)
					(thickness 0.15)
				)
				(justify left bottom)
				(hide yes)
			)
		)
		(property "Datasheet" ""
			(at 255.27 152.4 0)
			(effects
				(font
					(size 1.27 1.27)
					(thickness 0.15)
				)
				(justify left bottom)
				(hide yes)
			)
		)
		(property "Description" ""
			(at 246.38 139.7 0)
			(effects
				(font
					(size 1.27 1.27)
				)
				(hide yes)
			)
		)
		(property "Author" "Antmicro"
			(at 255.27 147.32 0)
			(effects
				(font
					(size 1.27 1.27)
					(thickness 0.15)
				)
				(justify left bottom)
				(hide yes)
			)
		)
		(property "License" "Apache-2.0"
			(at 255.27 149.86 0)
			(effects
				(font
					(size 1.27 1.27)
					(thickness 0.15)
				)
				(justify left bottom)
				(hide yes)
			)
		)
		(pin "1"
		)
		(instances
			(project "polarfire-som"
				(path ""
					(reference "#PWR0274")
					(unit 1)
				)
			)
		)
	)
	(symbol
		(lib_id "antmicroCapacitors0402:C_4u7_0402")
		(at 158.75 96.52 270)
		(unit 1)
		(exclude_from_sim no)
		(in_bom yes)
		(on_board yes)
		(dnp no)
		(property "Reference" "C113"
			(at 156.21 97.79 90)
			(effects
				(font
					(size 1.27 1.27)
					(thickness 0.15)
				)
				(justify right)
			)
		)
		(property "Value" "C_4u7_0402"
			(at 148.59 116.84 0)
			(effects
				(font
					(size 1.27 1.27)
					(thickness 0.15)
				)
				(justify left bottom)
				(hide yes)
			)
		)
		(property "Footprint" "antmicro-footprints:C_0402_1005Metric"
			(at 146.05 116.84 0)
			(effects
				(font
					(size 1.27 1.27)
					(thickness 0.15)
				)
				(justify left bottom)
				(hide yes)
			)
		)
		(property "Datasheet" "https://www.murata.com/products/productdetail?partno=GRM155R61A475MEAA%23"
			(at 143.51 116.84 0)
			(effects
				(font
					(size 1.27 1.27)
					(thickness 0.15)
				)
				(justify left bottom)
				(hide yes)
			)
		)
		(property "Description" "SMD Multilayer Ceramic Capacitor, 4.7 µF, 10 V, 0402 [1005 Metric], ± 20%, X5R, GRM Series"
			(at 158.75 96.52 0)
			(effects
				(font
					(size 1.27 1.27)
				)
				(hide yes)
			)
		)
		(property "MPN" "GRM155R61A475MEAAD"
			(at 140.97 116.84 0)
			(effects
				(font
					(size 1.27 1.27)
					(thickness 0.15)
				)
				(justify left bottom)
				(hide yes)
			)
		)
		(property "Manufacturer" "Murata"
			(at 138.43 116.84 0)
			(effects
				(font
					(size 1.27 1.27)
					(thickness 0.15)
				)
				(justify left bottom)
				(hide yes)
			)
		)
		(property "License" "Apache-2.0"
			(at 135.89 116.84 0)
			(effects
				(font
					(size 1.27 1.27)
					(thickness 0.15)
				)
				(justify left bottom)
				(hide yes)
			)
		)
		(property "Author" "Antmicro"
			(at 133.35 116.84 0)
			(effects
				(font
					(size 1.27 1.27)
					(thickness 0.15)
				)
				(justify left bottom)
				(hide yes)
			)
		)
		(property "Val" "4u7"
			(at 156.21 100.33 90)
			(effects
				(font
					(size 1.27 1.27)
					(thickness 0.15)
				)
				(justify right)
			)
		)
		(property "Voltage" ""
			(at 130.81 116.84 0)
			(effects
				(font
					(size 1.27 1.27)
				)
				(justify left bottom)
				(hide yes)
			)
		)
		(property "Dielectric" ""
			(at 128.27 116.84 0)
			(effects
				(font
					(size 1.27 1.27)
				)
				(justify left bottom)
				(hide yes)
			)
		)
		(property "Public" ""
			(at 125.73 116.84 0)
			(effects
				(font
					(size 1.27 1.27)
				)
				(justify left bottom)
				(hide yes)
			)
		)
		(pin "1"
		)
		(pin "2"
		)
		(instances
			(project "polarfire-som"
				(path ""
					(reference "C113")
					(unit 1)
				)
			)
		)
	)
	(symbol
		(lib_id "antmicroResistors0402:R_4k75_0.5%_0402")
		(at 238.76 138.43 0)
		(unit 1)
		(exclude_from_sim no)
		(in_bom yes)
		(on_board yes)
		(dnp no)
		(property "Reference" "R153"
			(at 236.22 137.16 0)
			(effects
				(font
					(size 1.27 1.27)
					(thickness 0.15)
				)
			)
		)
		(property "Value" "R_4k75_0.5%_0402"
			(at 259.08 151.13 0)
			(effects
				(font
					(size 1.27 1.27)
					(thickness 0.15)
				)
				(justify left bottom)
				(hide yes)
			)
		)
		(property "Footprint" "antmicro-footprints:R_0402_1005Metric"
			(at 259.08 153.67 0)
			(effects
				(font
					(size 1.27 1.27)
					(thickness 0.15)
				)
				(justify left bottom)
				(hide yes)
			)
		)
		(property "Datasheet" "https://industrial.panasonic.com/cdbs/www-data/pdf/RDQ0000/ast-ind-151033.pdf"
			(at 259.08 156.21 0)
			(effects
				(font
					(size 1.27 1.27)
					(thickness 0.15)
				)
				(justify left bottom)
				(hide yes)
			)
		)
		(property "Description" "SMD Chip Resistor, 4.75 kohm, ± 0.5%, 100 mW, 0402 [1005 Metric], Thick Film, High Temperature"
			(at 238.76 138.43 0)
			(effects
				(font
					(size 1.27 1.27)
				)
				(hide yes)
			)
		)
		(property "MPN" "ERJ-H2RD4751X"
			(at 259.08 158.75 0)
			(effects
				(font
					(size 1.27 1.27)
					(thickness 0.15)
				)
				(justify left bottom)
				(hide yes)
			)
		)
		(property "Manufacturer" "Panasonic"
			(at 259.08 161.29 0)
			(effects
				(font
					(size 1.27 1.27)
					(thickness 0.15)
				)
				(justify left bottom)
				(hide yes)
			)
		)
		(property "License" "Apache-2.0"
			(at 259.08 163.83 0)
			(effects
				(font
					(size 1.27 1.27)
					(thickness 0.15)
				)
				(justify left bottom)
				(hide yes)
			)
		)
		(property "Author" "Antmicro"
			(at 259.08 166.37 0)
			(effects
				(font
					(size 1.27 1.27)
					(thickness 0.15)
				)
				(justify left bottom)
				(hide yes)
			)
		)
		(property "Val" "4k75"
			(at 246.38 137.16 0)
			(effects
				(font
					(size 1.27 1.27)
					(thickness 0.15)
				)
			)
		)
		(property "Tolerance" "0.5%"
			(at 259.08 148.59 0)
			(effects
				(font
					(size 1.27 1.27)
				)
				(justify left bottom)
				(hide yes)
			)
		)
		(property "Public" ""
			(at 259.08 168.91 0)
			(effects
				(font
					(size 1.27 1.27)
				)
				(justify left bottom)
				(hide yes)
			)
		)
		(pin "1"
		)
		(pin "2"
		)
		(instances
			(project "polarfire-som"
				(path ""
					(reference "R153")
					(unit 1)
				)
			)
		)
	)
	(symbol
		(lib_id "antmicroTestPoints:TP_0.75mm_SMD")
		(at 233.68 124.46 0)
		(unit 1)
		(exclude_from_sim no)
		(in_bom no)
		(on_board yes)
		(dnp no)
		(property "Reference" "TP32"
			(at 240.665 124.46 0)
			(effects
				(font
					(size 1.27 1.27)
					(thickness 0.15)
				)
			)
		)
		(property "Value" "TP_0.75mm_SMD"
			(at 244.475 128.27 0)
			(effects
				(font
					(size 1.27 1.27)
					(thickness 0.15)
				)
				(justify left bottom)
				(hide yes)
			)
		)
		(property "Footprint" "antmicro-footprints:TP_SMD_0.75mm"
			(at 244.475 130.81 0)
			(effects
				(font
					(size 1.27 1.27)
					(thickness 0.15)
				)
				(justify left bottom)
				(hide yes)
			)
		)
		(property "Datasheet" ""
			(at 251.46 137.16 0)
			(effects
				(font
					(size 1.27 1.27)
					(thickness 0.15)
				)
				(justify left bottom)
				(hide yes)
			)
		)
		(property "Description" "SMT test point"
			(at 233.68 124.46 0)
			(effects
				(font
					(size 1.27 1.27)
				)
				(hide yes)
			)
		)
		(property "MPN" ""
			(at 244.475 135.89 0)
			(effects
				(font
					(size 1.27 1.27)
					(thickness 0.15)
				)
				(justify left bottom)
				(hide yes)
			)
		)
		(property "Manufacturer" ""
			(at 244.475 130.81 0)
			(effects
				(font
					(size 1.27 1.27)
					(thickness 0.15)
				)
				(justify left bottom)
				(hide yes)
			)
		)
		(property "Author" "Antmicro"
			(at 244.475 133.35 0)
			(effects
				(font
					(size 1.27 1.27)
					(thickness 0.15)
				)
				(justify left bottom)
				(hide yes)
			)
		)
		(property "License" "Apache-2.0"
			(at 244.475 135.89 0)
			(effects
				(font
					(size 1.27 1.27)
					(thickness 0.15)
				)
				(justify left bottom)
				(hide yes)
			)
		)
		(property "Public" "False"
			(at 243.84 138.43 0)
			(effects
				(font
					(size 1.27 1.27)
				)
				(justify left bottom)
				(hide yes)
			)
		)
		(pin "1"
		)
		(instances
			(project "polarfire-som"
				(path ""
					(reference "TP32")
					(unit 1)
				)
			)
		)
	)
	(symbol
		(lib_id "antmicropower:+3V3")
		(at 35.56 231.14 0)
		(unit 1)
		(exclude_from_sim no)
		(in_bom yes)
		(on_board yes)
		(dnp no)
		(property "Reference" "#PWR0347"
			(at 50.8 233.68 0)
			(effects
				(font
					(size 1.27 1.27)
					(thickness 0.15)
				)
				(justify left bottom)
				(hide yes)
			)
		)
		(property "Value" "+3V3"
			(at 35.56 227.33 0)
			(effects
				(font
					(size 1.27 1.27)
					(thickness 0.15)
				)
			)
		)
		(property "Footprint" ""
			(at 50.8 238.76 0)
			(effects
				(font
					(size 1.27 1.27)
					(thickness 0.15)
				)
				(justify left bottom)
				(hide yes)
			)
		)
		(property "Datasheet" ""
			(at 50.8 241.3 0)
			(effects
				(font
					(size 1.27 1.27)
					(thickness 0.15)
				)
				(justify left bottom)
				(hide yes)
			)
		)
		(property "Description" ""
			(at 35.56 231.14 0)
			(effects
				(font
					(size 1.27 1.27)
				)
				(hide yes)
			)
		)
		(property "Author" "Antmicro"
			(at 50.8 238.76 0)
			(effects
				(font
					(size 1.27 1.27)
					(thickness 0.15)
				)
				(justify left bottom)
				(hide yes)
			)
		)
		(property "License" "Apache-2.0"
			(at 50.8 241.3 0)
			(effects
				(font
					(size 1.27 1.27)
					(thickness 0.15)
				)
				(justify left bottom)
				(hide yes)
			)
		)
		(pin "1"
		)
		(instances
			(project "polarfire-som"
				(path ""
					(reference "#PWR0347")
					(unit 1)
				)
			)
		)
	)
	(symbol
		(lib_id "antmicropower:GND")
		(at 158.75 102.87 0)
		(unit 1)
		(exclude_from_sim no)
		(in_bom yes)
		(on_board yes)
		(dnp no)
		(property "Reference" "#PWR0221"
			(at 167.64 105.41 0)
			(effects
				(font
					(size 1.27 1.27)
					(thickness 0.15)
				)
				(justify left bottom)
				(hide yes)
			)
		)
		(property "Value" "GND"
			(at 158.75 106.68 0)
			(effects
				(font
					(size 1.27 1.27)
					(thickness 0.15)
				)
			)
		)
		(property "Footprint" ""
			(at 167.64 110.49 0)
			(effects
				(font
					(size 1.27 1.27)
					(thickness 0.15)
				)
				(justify left bottom)
				(hide yes)
			)
		)
		(property "Datasheet" ""
			(at 167.64 115.57 0)
			(effects
				(font
					(size 1.27 1.27)
					(thickness 0.15)
				)
				(justify left bottom)
				(hide yes)
			)
		)
		(property "Description" ""
			(at 158.75 102.87 0)
			(effects
				(font
					(size 1.27 1.27)
				)
				(hide yes)
			)
		)
		(property "Author" "Antmicro"
			(at 167.64 110.49 0)
			(effects
				(font
					(size 1.27 1.27)
					(thickness 0.15)
				)
				(justify left bottom)
				(hide yes)
			)
		)
		(property "License" "Apache-2.0"
			(at 167.64 113.03 0)
			(effects
				(font
					(size 1.27 1.27)
					(thickness 0.15)
				)
				(justify left bottom)
				(hide yes)
			)
		)
		(pin "1"
		)
		(instances
			(project "polarfire-som"
				(path ""
					(reference "#PWR0221")
					(unit 1)
				)
			)
		)
	)
	(symbol
		(lib_id "antmicroTestPoints:TP_0.75mm_SMD")
		(at 180.34 121.92 180)
		(unit 1)
		(exclude_from_sim no)
		(in_bom no)
		(on_board yes)
		(dnp no)
		(property "Reference" "TP15"
			(at 173.355 121.92 0)
			(effects
				(font
					(size 1.27 1.27)
					(thickness 0.15)
				)
			)
		)
		(property "Value" "TP_0.75mm_SMD"
			(at 169.545 118.11 0)
			(effects
				(font
					(size 1.27 1.27)
					(thickness 0.15)
				)
				(justify left bottom)
				(hide yes)
			)
		)
		(property "Footprint" "antmicro-footprints:TP_SMD_0.75mm"
			(at 169.545 115.57 0)
			(effects
				(font
					(size 1.27 1.27)
					(thickness 0.15)
				)
				(justify left bottom)
				(hide yes)
			)
		)
		(property "Datasheet" ""
			(at 162.56 109.22 0)
			(effects
				(font
					(size 1.27 1.27)
					(thickness 0.15)
				)
				(justify left bottom)
				(hide yes)
			)
		)
		(property "Description" "SMT test point"
			(at 180.34 121.92 0)
			(effects
				(font
					(size 1.27 1.27)
				)
				(hide yes)
			)
		)
		(property "MPN" ""
			(at 169.545 110.49 0)
			(effects
				(font
					(size 1.27 1.27)
					(thickness 0.15)
				)
				(justify left bottom)
				(hide yes)
			)
		)
		(property "Manufacturer" ""
			(at 169.545 115.57 0)
			(effects
				(font
					(size 1.27 1.27)
					(thickness 0.15)
				)
				(justify left bottom)
				(hide yes)
			)
		)
		(property "Author" "Antmicro"
			(at 169.545 113.03 0)
			(effects
				(font
					(size 1.27 1.27)
					(thickness 0.15)
				)
				(justify left bottom)
				(hide yes)
			)
		)
		(property "License" "Apache-2.0"
			(at 169.545 110.49 0)
			(effects
				(font
					(size 1.27 1.27)
					(thickness 0.15)
				)
				(justify left bottom)
				(hide yes)
			)
		)
		(property "Public" "False"
			(at 170.18 107.95 0)
			(effects
				(font
					(size 1.27 1.27)
				)
				(justify left bottom)
				(hide yes)
			)
		)
		(pin "1"
		)
		(instances
			(project "polarfire-som"
				(path ""
					(reference "TP15")
					(unit 1)
				)
			)
		)
	)
	(symbol
		(lib_id "antmicroResistors0402:R_10k_0402")
		(at 257.81 241.3 90)
		(unit 1)
		(exclude_from_sim no)
		(in_bom yes)
		(on_board yes)
		(dnp no)
		(property "Reference" "R146"
			(at 259.08 237.49 90)
			(effects
				(font
					(size 1.27 1.27)
					(thickness 0.15)
				)
				(justify right)
			)
		)
		(property "Value" "R_10k_0402"
			(at 270.51 220.98 0)
			(effects
				(font
					(size 1.27 1.27)
					(thickness 0.15)
				)
				(justify left bottom)
				(hide yes)
			)
		)
		(property "Footprint" "antmicro-footprints:R_0402_1005Metric"
			(at 273.05 220.98 0)
			(effects
				(font
					(size 1.27 1.27)
					(thickness 0.15)
				)
				(justify left bottom)
				(hide yes)
			)
		)
		(property "Datasheet" "https://www.bourns.com/docs/product-datasheets/cr.pdf"
			(at 275.59 220.98 0)
			(effects
				(font
					(size 1.27 1.27)
					(thickness 0.15)
				)
				(justify left bottom)
				(hide yes)
			)
		)
		(property "Description" "SMD Chip Resistor, 10 kohm, ± 1%, 62.5 mW, 0402 [1005 Metric], Thick Film, General Purpose"
			(at 257.81 241.3 0)
			(effects
				(font
					(size 1.27 1.27)
				)
				(hide yes)
			)
		)
		(property "MPN" "CR0402-FX-1002GLF"
			(at 278.13 220.98 0)
			(effects
				(font
					(size 1.27 1.27)
					(thickness 0.15)
				)
				(justify left bottom)
				(hide yes)
			)
		)
		(property "Manufacturer" "Bourns"
			(at 280.67 220.98 0)
			(effects
				(font
					(size 1.27 1.27)
					(thickness 0.15)
				)
				(justify left bottom)
				(hide yes)
			)
		)
		(property "License" "Apache-2.0"
			(at 283.21 220.98 0)
			(effects
				(font
					(size 1.27 1.27)
					(thickness 0.15)
				)
				(justify left bottom)
				(hide yes)
			)
		)
		(property "Author" "Antmicro"
			(at 285.75 220.98 0)
			(effects
				(font
					(size 1.27 1.27)
					(thickness 0.15)
				)
				(justify left bottom)
				(hide yes)
			)
		)
		(property "Val" "10k"
			(at 259.08 240.03 90)
			(effects
				(font
					(size 1.27 1.27)
					(thickness 0.15)
				)
				(justify right)
			)
		)
		(property "Tolerance" "1%"
			(at 267.97 220.98 0)
			(effects
				(font
					(size 1.27 1.27)
				)
				(justify left bottom)
				(hide yes)
			)
		)
		(property "Public" ""
			(at 288.29 220.98 0)
			(effects
				(font
					(size 1.27 1.27)
				)
				(justify left bottom)
				(hide yes)
			)
		)
		(pin "1"
		)
		(pin "2"
		)
		(instances
			(project "polarfire-som"
				(path ""
					(reference "R146")
					(unit 1)
				)
			)
		)
	)
	(symbol
		(lib_id "antmicropower:GND")
		(at 130.81 242.57 0)
		(unit 1)
		(exclude_from_sim no)
		(in_bom yes)
		(on_board yes)
		(dnp no)
		(property "Reference" "#PWR0269"
			(at 139.7 245.11 0)
			(effects
				(font
					(size 1.27 1.27)
					(thickness 0.15)
				)
				(justify left bottom)
				(hide yes)
			)
		)
		(property "Value" "GND"
			(at 130.81 246.38 0)
			(effects
				(font
					(size 1.27 1.27)
					(thickness 0.15)
				)
			)
		)
		(property "Footprint" ""
			(at 139.7 250.19 0)
			(effects
				(font
					(size 1.27 1.27)
					(thickness 0.15)
				)
				(justify left bottom)
				(hide yes)
			)
		)
		(property "Datasheet" ""
			(at 139.7 255.27 0)
			(effects
				(font
					(size 1.27 1.27)
					(thickness 0.15)
				)
				(justify left bottom)
				(hide yes)
			)
		)
		(property "Description" ""
			(at 130.81 242.57 0)
			(effects
				(font
					(size 1.27 1.27)
				)
				(hide yes)
			)
		)
		(property "Author" "Antmicro"
			(at 139.7 250.19 0)
			(effects
				(font
					(size 1.27 1.27)
					(thickness 0.15)
				)
				(justify left bottom)
				(hide yes)
			)
		)
		(property "License" "Apache-2.0"
			(at 139.7 252.73 0)
			(effects
				(font
					(size 1.27 1.27)
					(thickness 0.15)
				)
				(justify left bottom)
				(hide yes)
			)
		)
		(pin "1"
		)
		(instances
			(project "polarfire-som"
				(path ""
					(reference "#PWR0269")
					(unit 1)
				)
			)
		)
	)
	(symbol
		(lib_id "antmicroCapacitors0402:C_100n_0402")
		(at 209.55 236.22 90)
		(unit 1)
		(exclude_from_sim no)
		(in_bom yes)
		(on_board yes)
		(dnp no)
		(property "Reference" "C231"
			(at 210.82 232.41 90)
			(effects
				(font
					(size 1.27 1.27)
					(thickness 0.15)
				)
				(justify right)
			)
		)
		(property "Value" "C_100n_0402"
			(at 219.71 215.9 0)
			(effects
				(font
					(size 1.27 1.27)
					(thickness 0.15)
				)
				(justify left bottom)
				(hide yes)
			)
		)
		(property "Footprint" "antmicro-footprints:C_0402_1005Metric"
			(at 222.25 215.9 0)
			(effects
				(font
					(size 1.27 1.27)
					(thickness 0.15)
				)
				(justify left bottom)
				(hide yes)
			)
		)
		(property "Datasheet" "https://www.murata.com/products/productdetail?partno=GRM155R61H104KE14%23"
			(at 224.79 215.9 0)
			(effects
				(font
					(size 1.27 1.27)
					(thickness 0.15)
				)
				(justify left bottom)
				(hide yes)
			)
		)
		(property "Description" "SMD Multilayer Ceramic Capacitor, 0.1 µF, 50 V, 0402 [1005 Metric], ± 10%, X5R, GRM Series"
			(at 209.55 236.22 0)
			(effects
				(font
					(size 1.27 1.27)
				)
				(hide yes)
			)
		)
		(property "MPN" "GRM155R61H104KE14D"
			(at 227.33 215.9 0)
			(effects
				(font
					(size 1.27 1.27)
					(thickness 0.15)
				)
				(justify left bottom)
				(hide yes)
			)
		)
		(property "Manufacturer" "Murata"
			(at 229.87 215.9 0)
			(effects
				(font
					(size 1.27 1.27)
					(thickness 0.15)
				)
				(justify left bottom)
				(hide yes)
			)
		)
		(property "License" "Apache-2.0"
			(at 232.41 215.9 0)
			(effects
				(font
					(size 1.27 1.27)
					(thickness 0.15)
				)
				(justify left bottom)
				(hide yes)
			)
		)
		(property "Author" "Antmicro"
			(at 234.95 215.9 0)
			(effects
				(font
					(size 1.27 1.27)
					(thickness 0.15)
				)
				(justify left bottom)
				(hide yes)
			)
		)
		(property "Val" "100n"
			(at 215.9 234.95 90)
			(effects
				(font
					(size 1.27 1.27)
					(thickness 0.15)
				)
				(justify left bottom)
			)
		)
		(property "Voltage" "50V"
			(at 237.49 215.9 0)
			(effects
				(font
					(size 1.27 1.27)
				)
				(justify left bottom)
				(hide yes)
			)
		)
		(property "Dielectric" "X5R"
			(at 240.03 215.9 0)
			(effects
				(font
					(size 1.27 1.27)
				)
				(justify left bottom)
				(hide yes)
			)
		)
		(property "Public" ""
			(at 242.57 215.9 0)
			(effects
				(font
					(size 1.27 1.27)
				)
				(justify left bottom)
				(hide yes)
			)
		)
		(pin "1"
		)
		(pin "2"
		)
		(instances
			(project "polarfire-som"
				(path ""
					(reference "C231")
					(unit 1)
				)
			)
		)
	)
	(symbol
		(lib_id "antmicroTestPoints:TP_0.75mm_SMD")
		(at 233.68 119.38 0)
		(unit 1)
		(exclude_from_sim no)
		(in_bom no)
		(on_board yes)
		(dnp no)
		(property "Reference" "TP30"
			(at 240.665 119.38 0)
			(effects
				(font
					(size 1.27 1.27)
					(thickness 0.15)
				)
			)
		)
		(property "Value" "TP_0.75mm_SMD"
			(at 244.475 123.19 0)
			(effects
				(font
					(size 1.27 1.27)
					(thickness 0.15)
				)
				(justify left bottom)
				(hide yes)
			)
		)
		(property "Footprint" "antmicro-footprints:TP_SMD_0.75mm"
			(at 244.475 125.73 0)
			(effects
				(font
					(size 1.27 1.27)
					(thickness 0.15)
				)
				(justify left bottom)
				(hide yes)
			)
		)
		(property "Datasheet" ""
			(at 251.46 132.08 0)
			(effects
				(font
					(size 1.27 1.27)
					(thickness 0.15)
				)
				(justify left bottom)
				(hide yes)
			)
		)
		(property "Description" "SMT test point"
			(at 233.68 119.38 0)
			(effects
				(font
					(size 1.27 1.27)
				)
				(hide yes)
			)
		)
		(property "MPN" ""
			(at 244.475 130.81 0)
			(effects
				(font
					(size 1.27 1.27)
					(thickness 0.15)
				)
				(justify left bottom)
				(hide yes)
			)
		)
		(property "Manufacturer" ""
			(at 244.475 125.73 0)
			(effects
				(font
					(size 1.27 1.27)
					(thickness 0.15)
				)
				(justify left bottom)
				(hide yes)
			)
		)
		(property "Author" "Antmicro"
			(at 244.475 128.27 0)
			(effects
				(font
					(size 1.27 1.27)
					(thickness 0.15)
				)
				(justify left bottom)
				(hide yes)
			)
		)
		(property "License" "Apache-2.0"
			(at 244.475 130.81 0)
			(effects
				(font
					(size 1.27 1.27)
					(thickness 0.15)
				)
				(justify left bottom)
				(hide yes)
			)
		)
		(property "Public" "False"
			(at 243.84 133.35 0)
			(effects
				(font
					(size 1.27 1.27)
				)
				(justify left bottom)
				(hide yes)
			)
		)
		(pin "1"
		)
		(instances
			(project "polarfire-som"
				(path ""
					(reference "TP30")
					(unit 1)
				)
			)
		)
	)
	(symbol
		(lib_id "antmicropower:GND")
		(at 209.55 238.76 0)
		(unit 1)
		(exclude_from_sim no)
		(in_bom yes)
		(on_board yes)
		(dnp no)
		(property "Reference" "#PWR0270"
			(at 218.44 241.3 0)
			(effects
				(font
					(size 1.27 1.27)
					(thickness 0.15)
				)
				(justify left bottom)
				(hide yes)
			)
		)
		(property "Value" "GND"
			(at 209.55 242.57 0)
			(effects
				(font
					(size 1.27 1.27)
					(thickness 0.15)
				)
			)
		)
		(property "Footprint" ""
			(at 218.44 246.38 0)
			(effects
				(font
					(size 1.27 1.27)
					(thickness 0.15)
				)
				(justify left bottom)
				(hide yes)
			)
		)
		(property "Datasheet" ""
			(at 218.44 251.46 0)
			(effects
				(font
					(size 1.27 1.27)
					(thickness 0.15)
				)
				(justify left bottom)
				(hide yes)
			)
		)
		(property "Description" ""
			(at 209.55 238.76 0)
			(effects
				(font
					(size 1.27 1.27)
				)
				(hide yes)
			)
		)
		(property "Author" "Antmicro"
			(at 218.44 246.38 0)
			(effects
				(font
					(size 1.27 1.27)
					(thickness 0.15)
				)
				(justify left bottom)
				(hide yes)
			)
		)
		(property "License" "Apache-2.0"
			(at 218.44 248.92 0)
			(effects
				(font
					(size 1.27 1.27)
					(thickness 0.15)
				)
				(justify left bottom)
				(hide yes)
			)
		)
		(pin "1"
		)
		(instances
			(project "polarfire-som"
				(path ""
					(reference "#PWR0270")
					(unit 1)
				)
			)
		)
	)
	(symbol
		(lib_id "antmicroCapacitors0402:C_100n_0402")
		(at 130.81 241.3 90)
		(unit 1)
		(exclude_from_sim no)
		(in_bom yes)
		(on_board yes)
		(dnp no)
		(property "Reference" "C227"
			(at 132.08 237.49 90)
			(effects
				(font
					(size 1.27 1.27)
					(thickness 0.15)
				)
				(justify right)
			)
		)
		(property "Value" "C_100n_0402"
			(at 140.97 220.98 0)
			(effects
				(font
					(size 1.27 1.27)
					(thickness 0.15)
				)
				(justify left bottom)
				(hide yes)
			)
		)
		(property "Footprint" "antmicro-footprints:C_0402_1005Metric"
			(at 143.51 220.98 0)
			(effects
				(font
					(size 1.27 1.27)
					(thickness 0.15)
				)
				(justify left bottom)
				(hide yes)
			)
		)
		(property "Datasheet" "https://www.murata.com/products/productdetail?partno=GRM155R61H104KE14%23"
			(at 146.05 220.98 0)
			(effects
				(font
					(size 1.27 1.27)
					(thickness 0.15)
				)
				(justify left bottom)
				(hide yes)
			)
		)
		(property "Description" "SMD Multilayer Ceramic Capacitor, 0.1 µF, 50 V, 0402 [1005 Metric], ± 10%, X5R, GRM Series"
			(at 130.81 241.3 0)
			(effects
				(font
					(size 1.27 1.27)
				)
				(hide yes)
			)
		)
		(property "MPN" "GRM155R61H104KE14D"
			(at 148.59 220.98 0)
			(effects
				(font
					(size 1.27 1.27)
					(thickness 0.15)
				)
				(justify left bottom)
				(hide yes)
			)
		)
		(property "Manufacturer" "Murata"
			(at 151.13 220.98 0)
			(effects
				(font
					(size 1.27 1.27)
					(thickness 0.15)
				)
				(justify left bottom)
				(hide yes)
			)
		)
		(property "License" "Apache-2.0"
			(at 153.67 220.98 0)
			(effects
				(font
					(size 1.27 1.27)
					(thickness 0.15)
				)
				(justify left bottom)
				(hide yes)
			)
		)
		(property "Author" "Antmicro"
			(at 156.21 220.98 0)
			(effects
				(font
					(size 1.27 1.27)
					(thickness 0.15)
				)
				(justify left bottom)
				(hide yes)
			)
		)
		(property "Val" "100n"
			(at 137.16 240.03 90)
			(effects
				(font
					(size 1.27 1.27)
					(thickness 0.15)
				)
				(justify left bottom)
			)
		)
		(property "Voltage" "50V"
			(at 158.75 220.98 0)
			(effects
				(font
					(size 1.27 1.27)
				)
				(justify left bottom)
				(hide yes)
			)
		)
		(property "Dielectric" "X5R"
			(at 161.29 220.98 0)
			(effects
				(font
					(size 1.27 1.27)
				)
				(justify left bottom)
				(hide yes)
			)
		)
		(property "Public" ""
			(at 163.83 220.98 0)
			(effects
				(font
					(size 1.27 1.27)
				)
				(justify left bottom)
				(hide yes)
			)
		)
		(pin "1"
		)
		(pin "2"
		)
		(instances
			(project "polarfire-som"
				(path ""
					(reference "C227")
					(unit 1)
				)
			)
		)
	)
	(symbol
		(lib_id "antmicroTestPoints:TP_0.75mm_SMD")
		(at 233.68 116.84 0)
		(unit 1)
		(exclude_from_sim no)
		(in_bom no)
		(on_board yes)
		(dnp no)
		(property "Reference" "TP29"
			(at 240.665 116.84 0)
			(effects
				(font
					(size 1.27 1.27)
					(thickness 0.15)
				)
			)
		)
		(property "Value" "TP_0.75mm_SMD"
			(at 244.475 120.65 0)
			(effects
				(font
					(size 1.27 1.27)
					(thickness 0.15)
				)
				(justify left bottom)
				(hide yes)
			)
		)
		(property "Footprint" "antmicro-footprints:TP_SMD_0.75mm"
			(at 244.475 123.19 0)
			(effects
				(font
					(size 1.27 1.27)
					(thickness 0.15)
				)
				(justify left bottom)
				(hide yes)
			)
		)
		(property "Datasheet" ""
			(at 251.46 129.54 0)
			(effects
				(font
					(size 1.27 1.27)
					(thickness 0.15)
				)
				(justify left bottom)
				(hide yes)
			)
		)
		(property "Description" "SMT test point"
			(at 233.68 116.84 0)
			(effects
				(font
					(size 1.27 1.27)
				)
				(hide yes)
			)
		)
		(property "MPN" ""
			(at 244.475 128.27 0)
			(effects
				(font
					(size 1.27 1.27)
					(thickness 0.15)
				)
				(justify left bottom)
				(hide yes)
			)
		)
		(property "Manufacturer" ""
			(at 244.475 123.19 0)
			(effects
				(font
					(size 1.27 1.27)
					(thickness 0.15)
				)
				(justify left bottom)
				(hide yes)
			)
		)
		(property "Author" "Antmicro"
			(at 244.475 125.73 0)
			(effects
				(font
					(size 1.27 1.27)
					(thickness 0.15)
				)
				(justify left bottom)
				(hide yes)
			)
		)
		(property "License" "Apache-2.0"
			(at 244.475 128.27 0)
			(effects
				(font
					(size 1.27 1.27)
					(thickness 0.15)
				)
				(justify left bottom)
				(hide yes)
			)
		)
		(property "Public" "False"
			(at 243.84 130.81 0)
			(effects
				(font
					(size 1.27 1.27)
				)
				(justify left bottom)
				(hide yes)
			)
		)
		(pin "1"
		)
		(instances
			(project "polarfire-som"
				(path ""
					(reference "TP29")
					(unit 1)
				)
			)
		)
	)
	(symbol
		(lib_id "antmicroTestPoints:TP_0.75mm_SMD")
		(at 180.34 116.84 180)
		(unit 1)
		(exclude_from_sim no)
		(in_bom no)
		(on_board yes)
		(dnp no)
		(property "Reference" "TP13"
			(at 173.355 116.84 0)
			(effects
				(font
					(size 1.27 1.27)
					(thickness 0.15)
				)
			)
		)
		(property "Value" "TP_0.75mm_SMD"
			(at 169.545 113.03 0)
			(effects
				(font
					(size 1.27 1.27)
					(thickness 0.15)
				)
				(justify left bottom)
				(hide yes)
			)
		)
		(property "Footprint" "antmicro-footprints:TP_SMD_0.75mm"
			(at 169.545 110.49 0)
			(effects
				(font
					(size 1.27 1.27)
					(thickness 0.15)
				)
				(justify left bottom)
				(hide yes)
			)
		)
		(property "Datasheet" ""
			(at 162.56 104.14 0)
			(effects
				(font
					(size 1.27 1.27)
					(thickness 0.15)
				)
				(justify left bottom)
				(hide yes)
			)
		)
		(property "Description" "SMT test point"
			(at 180.34 116.84 0)
			(effects
				(font
					(size 1.27 1.27)
				)
				(hide yes)
			)
		)
		(property "MPN" ""
			(at 169.545 105.41 0)
			(effects
				(font
					(size 1.27 1.27)
					(thickness 0.15)
				)
				(justify left bottom)
				(hide yes)
			)
		)
		(property "Manufacturer" ""
			(at 169.545 110.49 0)
			(effects
				(font
					(size 1.27 1.27)
					(thickness 0.15)
				)
				(justify left bottom)
				(hide yes)
			)
		)
		(property "Author" "Antmicro"
			(at 169.545 107.95 0)
			(effects
				(font
					(size 1.27 1.27)
					(thickness 0.15)
				)
				(justify left bottom)
				(hide yes)
			)
		)
		(property "License" "Apache-2.0"
			(at 169.545 105.41 0)
			(effects
				(font
					(size 1.27 1.27)
					(thickness 0.15)
				)
				(justify left bottom)
				(hide yes)
			)
		)
		(property "Public" "False"
			(at 170.18 102.87 0)
			(effects
				(font
					(size 1.27 1.27)
				)
				(justify left bottom)
				(hide yes)
			)
		)
		(pin "1"
		)
		(instances
			(project "polarfire-som"
				(path ""
					(reference "TP13")
					(unit 1)
				)
			)
		)
	)
	(symbol
		(lib_id "antmicroCapacitors0402:C_100n_0402")
		(at 121.92 241.3 90)
		(unit 1)
		(exclude_from_sim no)
		(in_bom yes)
		(on_board yes)
		(dnp no)
		(property "Reference" "C228"
			(at 123.19 237.49 90)
			(effects
				(font
					(size 1.27 1.27)
					(thickness 0.15)
				)
				(justify right)
			)
		)
		(property "Value" "C_100n_0402"
			(at 132.08 220.98 0)
			(effects
				(font
					(size 1.27 1.27)
					(thickness 0.15)
				)
				(justify left bottom)
				(hide yes)
			)
		)
		(property "Footprint" "antmicro-footprints:C_0402_1005Metric"
			(at 134.62 220.98 0)
			(effects
				(font
					(size 1.27 1.27)
					(thickness 0.15)
				)
				(justify left bottom)
				(hide yes)
			)
		)
		(property "Datasheet" "https://www.murata.com/products/productdetail?partno=GRM155R61H104KE14%23"
			(at 137.16 220.98 0)
			(effects
				(font
					(size 1.27 1.27)
					(thickness 0.15)
				)
				(justify left bottom)
				(hide yes)
			)
		)
		(property "Description" "SMD Multilayer Ceramic Capacitor, 0.1 µF, 50 V, 0402 [1005 Metric], ± 10%, X5R, GRM Series"
			(at 121.92 241.3 0)
			(effects
				(font
					(size 1.27 1.27)
				)
				(hide yes)
			)
		)
		(property "MPN" "GRM155R61H104KE14D"
			(at 139.7 220.98 0)
			(effects
				(font
					(size 1.27 1.27)
					(thickness 0.15)
				)
				(justify left bottom)
				(hide yes)
			)
		)
		(property "Manufacturer" "Murata"
			(at 142.24 220.98 0)
			(effects
				(font
					(size 1.27 1.27)
					(thickness 0.15)
				)
				(justify left bottom)
				(hide yes)
			)
		)
		(property "License" "Apache-2.0"
			(at 144.78 220.98 0)
			(effects
				(font
					(size 1.27 1.27)
					(thickness 0.15)
				)
				(justify left bottom)
				(hide yes)
			)
		)
		(property "Author" "Antmicro"
			(at 147.32 220.98 0)
			(effects
				(font
					(size 1.27 1.27)
					(thickness 0.15)
				)
				(justify left bottom)
				(hide yes)
			)
		)
		(property "Val" "100n"
			(at 128.27 240.03 90)
			(effects
				(font
					(size 1.27 1.27)
					(thickness 0.15)
				)
				(justify left bottom)
			)
		)
		(property "Voltage" "50V"
			(at 149.86 220.98 0)
			(effects
				(font
					(size 1.27 1.27)
				)
				(justify left bottom)
				(hide yes)
			)
		)
		(property "Dielectric" "X5R"
			(at 152.4 220.98 0)
			(effects
				(font
					(size 1.27 1.27)
				)
				(justify left bottom)
				(hide yes)
			)
		)
		(property "Public" ""
			(at 154.94 220.98 0)
			(effects
				(font
					(size 1.27 1.27)
				)
				(justify left bottom)
				(hide yes)
			)
		)
		(pin "1"
		)
		(pin "2"
		)
		(instances
			(project "polarfire-som"
				(path ""
					(reference "C228")
					(unit 1)
				)
			)
		)
	)
	(symbol
		(lib_id "antmicropower:+3V3")
		(at 177.8 80.01 0)
		(unit 1)
		(exclude_from_sim no)
		(in_bom yes)
		(on_board yes)
		(dnp no)
		(property "Reference" "#PWR0272"
			(at 193.04 82.55 0)
			(effects
				(font
					(size 1.27 1.27)
					(thickness 0.15)
				)
				(justify left bottom)
				(hide yes)
			)
		)
		(property "Value" "+3V3"
			(at 177.8 76.2 0)
			(effects
				(font
					(size 1.27 1.27)
					(thickness 0.15)
				)
			)
		)
		(property "Footprint" ""
			(at 193.04 87.63 0)
			(effects
				(font
					(size 1.27 1.27)
					(thickness 0.15)
				)
				(justify left bottom)
				(hide yes)
			)
		)
		(property "Datasheet" ""
			(at 193.04 90.17 0)
			(effects
				(font
					(size 1.27 1.27)
					(thickness 0.15)
				)
				(justify left bottom)
				(hide yes)
			)
		)
		(property "Description" ""
			(at 177.8 80.01 0)
			(effects
				(font
					(size 1.27 1.27)
				)
				(hide yes)
			)
		)
		(property "Author" "Antmicro"
			(at 193.04 87.63 0)
			(effects
				(font
					(size 1.27 1.27)
					(thickness 0.15)
				)
				(justify left bottom)
				(hide yes)
			)
		)
		(property "License" "Apache-2.0"
			(at 193.04 90.17 0)
			(effects
				(font
					(size 1.27 1.27)
					(thickness 0.15)
				)
				(justify left bottom)
				(hide yes)
			)
		)
		(pin "1"
		)
		(instances
			(project "polarfire-som"
				(path ""
					(reference "#PWR0272")
					(unit 1)
				)
			)
		)
	)
	(symbol
		(lib_id "antmicroTestPoints:TP_0.75mm_SMD")
		(at 180.34 124.46 180)
		(unit 1)
		(exclude_from_sim no)
		(in_bom no)
		(on_board yes)
		(dnp no)
		(property "Reference" "TP16"
			(at 173.355 124.46 0)
			(effects
				(font
					(size 1.27 1.27)
					(thickness 0.15)
				)
			)
		)
		(property "Value" "TP_0.75mm_SMD"
			(at 169.545 120.65 0)
			(effects
				(font
					(size 1.27 1.27)
					(thickness 0.15)
				)
				(justify left bottom)
				(hide yes)
			)
		)
		(property "Footprint" "antmicro-footprints:TP_SMD_0.75mm"
			(at 169.545 118.11 0)
			(effects
				(font
					(size 1.27 1.27)
					(thickness 0.15)
				)
				(justify left bottom)
				(hide yes)
			)
		)
		(property "Datasheet" ""
			(at 162.56 111.76 0)
			(effects
				(font
					(size 1.27 1.27)
					(thickness 0.15)
				)
				(justify left bottom)
				(hide yes)
			)
		)
		(property "Description" "SMT test point"
			(at 180.34 124.46 0)
			(effects
				(font
					(size 1.27 1.27)
				)
				(hide yes)
			)
		)
		(property "MPN" ""
			(at 169.545 113.03 0)
			(effects
				(font
					(size 1.27 1.27)
					(thickness 0.15)
				)
				(justify left bottom)
				(hide yes)
			)
		)
		(property "Manufacturer" ""
			(at 169.545 118.11 0)
			(effects
				(font
					(size 1.27 1.27)
					(thickness 0.15)
				)
				(justify left bottom)
				(hide yes)
			)
		)
		(property "Author" "Antmicro"
			(at 169.545 115.57 0)
			(effects
				(font
					(size 1.27 1.27)
					(thickness 0.15)
				)
				(justify left bottom)
				(hide yes)
			)
		)
		(property "License" "Apache-2.0"
			(at 169.545 113.03 0)
			(effects
				(font
					(size 1.27 1.27)
					(thickness 0.15)
				)
				(justify left bottom)
				(hide yes)
			)
		)
		(property "Public" "False"
			(at 170.18 110.49 0)
			(effects
				(font
					(size 1.27 1.27)
				)
				(justify left bottom)
				(hide yes)
			)
		)
		(pin "1"
		)
		(instances
			(project "polarfire-som"
				(path ""
					(reference "TP16")
					(unit 1)
				)
			)
		)
	)
	(symbol
		(lib_id "antmicroTestPoints:TP_0.75mm_SMD")
		(at 180.34 135.89 180)
		(unit 1)
		(exclude_from_sim no)
		(in_bom no)
		(on_board yes)
		(dnp no)
		(property "Reference" "TP9"
			(at 173.355 135.89 0)
			(effects
				(font
					(size 1.27 1.27)
					(thickness 0.15)
				)
			)
		)
		(property "Value" "TP_0.75mm_SMD"
			(at 169.545 132.08 0)
			(effects
				(font
					(size 1.27 1.27)
					(thickness 0.15)
				)
				(justify left bottom)
				(hide yes)
			)
		)
		(property "Footprint" "antmicro-footprints:TP_SMD_0.75mm"
			(at 169.545 129.54 0)
			(effects
				(font
					(size 1.27 1.27)
					(thickness 0.15)
				)
				(justify left bottom)
				(hide yes)
			)
		)
		(property "Datasheet" ""
			(at 162.56 123.19 0)
			(effects
				(font
					(size 1.27 1.27)
					(thickness 0.15)
				)
				(justify left bottom)
				(hide yes)
			)
		)
		(property "Description" "SMT test point"
			(at 180.34 135.89 0)
			(effects
				(font
					(size 1.27 1.27)
				)
				(hide yes)
			)
		)
		(property "MPN" ""
			(at 169.545 124.46 0)
			(effects
				(font
					(size 1.27 1.27)
					(thickness 0.15)
				)
				(justify left bottom)
				(hide yes)
			)
		)
		(property "Manufacturer" ""
			(at 169.545 129.54 0)
			(effects
				(font
					(size 1.27 1.27)
					(thickness 0.15)
				)
				(justify left bottom)
				(hide yes)
			)
		)
		(property "Author" "Antmicro"
			(at 169.545 127 0)
			(effects
				(font
					(size 1.27 1.27)
					(thickness 0.15)
				)
				(justify left bottom)
				(hide yes)
			)
		)
		(property "License" "Apache-2.0"
			(at 169.545 124.46 0)
			(effects
				(font
					(size 1.27 1.27)
					(thickness 0.15)
				)
				(justify left bottom)
				(hide yes)
			)
		)
		(property "Public" "False"
			(at 170.18 121.92 0)
			(effects
				(font
					(size 1.27 1.27)
				)
				(justify left bottom)
				(hide yes)
			)
		)
		(pin "1"
		)
		(instances
			(project "polarfire-som"
				(path ""
					(reference "TP9")
					(unit 1)
				)
			)
		)
	)
	(symbol
		(lib_id "antmicroResistors0402:R_0R_0402")
		(at 236.22 85.09 0)
		(unit 1)
		(exclude_from_sim no)
		(in_bom yes)
		(on_board yes)
		(dnp no)
		(fields_autoplaced yes)
		(property "Reference" "R152"
			(at 238.76 78.74 0)
			(effects
				(font
					(size 1.27 1.27)
					(thickness 0.15)
				)
			)
		)
		(property "Value" "R_0R_0402"
			(at 256.54 97.79 0)
			(effects
				(font
					(size 1.27 1.27)
					(thickness 0.15)
				)
				(justify left bottom)
				(hide yes)
			)
		)
		(property "Footprint" "antmicro-footprints:R_0402_1005Metric"
			(at 256.54 100.33 0)
			(effects
				(font
					(size 1.27 1.27)
					(thickness 0.15)
				)
				(justify left bottom)
				(hide yes)
			)
		)
		(property "Datasheet" "https://industrial.panasonic.com/cdbs/www-data/pdf/RDA0000/AOA0000C301.pdf"
			(at 256.54 102.87 0)
			(effects
				(font
					(size 1.27 1.27)
					(thickness 0.15)
				)
				(justify left bottom)
				(hide yes)
			)
		)
		(property "Description" "SMD Chip Resistor, Jumper, 0 ohm, 100 mW, 0402 [1005 Metric], Thick Film, General Purpose"
			(at 236.22 85.09 0)
			(effects
				(font
					(size 1.27 1.27)
				)
				(hide yes)
			)
		)
		(property "MPN" "ERJ2GE0R00X"
			(at 256.54 105.41 0)
			(effects
				(font
					(size 1.27 1.27)
					(thickness 0.15)
				)
				(justify left bottom)
				(hide yes)
			)
		)
		(property "Manufacturer" "Panasonic"
			(at 256.54 107.95 0)
			(effects
				(font
					(size 1.27 1.27)
					(thickness 0.15)
				)
				(justify left bottom)
				(hide yes)
			)
		)
		(property "License" "Apache-2.0"
			(at 256.54 110.49 0)
			(effects
				(font
					(size 1.27 1.27)
					(thickness 0.15)
				)
				(justify left bottom)
				(hide yes)
			)
		)
		(property "Author" "Antmicro"
			(at 256.54 113.03 0)
			(effects
				(font
					(size 1.27 1.27)
					(thickness 0.15)
				)
				(justify left bottom)
				(hide yes)
			)
		)
		(property "Val" "0R"
			(at 238.76 81.28 0)
			(effects
				(font
					(size 1.27 1.27)
					(thickness 0.15)
				)
			)
		)
		(property "Tolerance" "~"
			(at 256.54 95.25 0)
			(effects
				(font
					(size 1.27 1.27)
				)
				(justify left bottom)
				(hide yes)
			)
		)
		(property "Current" "1A"
			(at 256.54 115.57 0)
			(effects
				(font
					(size 1.27 1.27)
					(thickness 0.15)
				)
				(justify left bottom)
				(hide yes)
			)
		)
		(property "Public" ""
			(at 256.54 115.57 0)
			(effects
				(font
					(size 1.27 1.27)
				)
				(justify left bottom)
				(hide yes)
			)
		)
		(pin "1"
		)
		(pin "2"
		)
		(instances
			(project "polarfire-som"
				(path ""
					(reference "R152")
					(unit 1)
				)
			)
		)
	)
	(symbol
		(lib_id "antmicroTestPoints:TP_0.75mm_SMD")
		(at 233.68 127 0)
		(unit 1)
		(exclude_from_sim no)
		(in_bom no)
		(on_board yes)
		(dnp no)
		(property "Reference" "TP33"
			(at 240.665 127 0)
			(effects
				(font
					(size 1.27 1.27)
					(thickness 0.15)
				)
			)
		)
		(property "Value" "TP_0.75mm_SMD"
			(at 244.475 130.81 0)
			(effects
				(font
					(size 1.27 1.27)
					(thickness 0.15)
				)
				(justify left bottom)
				(hide yes)
			)
		)
		(property "Footprint" "antmicro-footprints:TP_SMD_0.75mm"
			(at 244.475 133.35 0)
			(effects
				(font
					(size 1.27 1.27)
					(thickness 0.15)
				)
				(justify left bottom)
				(hide yes)
			)
		)
		(property "Datasheet" ""
			(at 251.46 139.7 0)
			(effects
				(font
					(size 1.27 1.27)
					(thickness 0.15)
				)
				(justify left bottom)
				(hide yes)
			)
		)
		(property "Description" "SMT test point"
			(at 233.68 127 0)
			(effects
				(font
					(size 1.27 1.27)
				)
				(hide yes)
			)
		)
		(property "MPN" ""
			(at 244.475 138.43 0)
			(effects
				(font
					(size 1.27 1.27)
					(thickness 0.15)
				)
				(justify left bottom)
				(hide yes)
			)
		)
		(property "Manufacturer" ""
			(at 244.475 133.35 0)
			(effects
				(font
					(size 1.27 1.27)
					(thickness 0.15)
				)
				(justify left bottom)
				(hide yes)
			)
		)
		(property "Author" "Antmicro"
			(at 244.475 135.89 0)
			(effects
				(font
					(size 1.27 1.27)
					(thickness 0.15)
				)
				(justify left bottom)
				(hide yes)
			)
		)
		(property "License" "Apache-2.0"
			(at 244.475 138.43 0)
			(effects
				(font
					(size 1.27 1.27)
					(thickness 0.15)
				)
				(justify left bottom)
				(hide yes)
			)
		)
		(property "Public" "False"
			(at 243.84 140.97 0)
			(effects
				(font
					(size 1.27 1.27)
				)
				(justify left bottom)
				(hide yes)
			)
		)
		(pin "1"
		)
		(instances
			(project "polarfire-som"
				(path ""
					(reference "TP33")
					(unit 1)
				)
			)
		)
	)
	(symbol
		(lib_id "antmicroCapacitors0402:C_100n_0402")
		(at 35.56 238.76 90)
		(unit 1)
		(exclude_from_sim no)
		(in_bom yes)
		(on_board yes)
		(dnp no)
		(property "Reference" "C229"
			(at 38.1 234.9435 90)
			(effects
				(font
					(size 1.27 1.27)
					(thickness 0.15)
				)
				(justify right)
			)
		)
		(property "Value" "C_100n_0402"
			(at 45.72 218.44 0)
			(effects
				(font
					(size 1.27 1.27)
					(thickness 0.15)
				)
				(justify left bottom)
				(hide yes)
			)
		)
		(property "Footprint" "antmicro-footprints:C_0402_1005Metric"
			(at 48.26 218.44 0)
			(effects
				(font
					(size 1.27 1.27)
					(thickness 0.15)
				)
				(justify left bottom)
				(hide yes)
			)
		)
		(property "Datasheet" "https://www.murata.com/products/productdetail?partno=GRM155R61H104KE14%23"
			(at 50.8 218.44 0)
			(effects
				(font
					(size 1.27 1.27)
					(thickness 0.15)
				)
				(justify left bottom)
				(hide yes)
			)
		)
		(property "Description" "SMD Multilayer Ceramic Capacitor, 0.1 µF, 50 V, 0402 [1005 Metric], ± 10%, X5R, GRM Series"
			(at 35.56 238.76 0)
			(effects
				(font
					(size 1.27 1.27)
				)
				(hide yes)
			)
		)
		(property "MPN" "GRM155R61H104KE14D"
			(at 53.34 218.44 0)
			(effects
				(font
					(size 1.27 1.27)
					(thickness 0.15)
				)
				(justify left bottom)
				(hide yes)
			)
		)
		(property "Manufacturer" "Murata"
			(at 55.88 218.44 0)
			(effects
				(font
					(size 1.27 1.27)
					(thickness 0.15)
				)
				(justify left bottom)
				(hide yes)
			)
		)
		(property "License" "Apache-2.0"
			(at 58.42 218.44 0)
			(effects
				(font
					(size 1.27 1.27)
					(thickness 0.15)
				)
				(justify left bottom)
				(hide yes)
			)
		)
		(property "Author" "Antmicro"
			(at 60.96 218.44 0)
			(effects
				(font
					(size 1.27 1.27)
					(thickness 0.15)
				)
				(justify left bottom)
				(hide yes)
			)
		)
		(property "Val" "100n"
			(at 43.18 236.855 90)
			(effects
				(font
					(size 1.27 1.27)
					(thickness 0.15)
				)
				(justify left bottom)
			)
		)
		(property "Voltage" "50V"
			(at 63.5 218.44 0)
			(effects
				(font
					(size 1.27 1.27)
				)
				(justify left bottom)
				(hide yes)
			)
		)
		(property "Dielectric" "X5R"
			(at 66.04 218.44 0)
			(effects
				(font
					(size 1.27 1.27)
				)
				(justify left bottom)
				(hide yes)
			)
		)
		(property "Public" ""
			(at 68.58 218.44 0)
			(effects
				(font
					(size 1.27 1.27)
				)
				(justify left bottom)
				(hide yes)
			)
		)
		(pin "1"
		)
		(pin "2"
		)
		(instances
			(project "polarfire-som"
				(path ""
					(reference "C229")
					(unit 1)
				)
			)
		)
	)
	(symbol
		(lib_id "antmicroTestPoints:TP_0.75mm_SMD")
		(at 233.68 95.25 0)
		(unit 1)
		(exclude_from_sim no)
		(in_bom no)
		(on_board yes)
		(dnp no)
		(property "Reference" "TP28"
			(at 240.665 95.25 0)
			(effects
				(font
					(size 1.27 1.27)
					(thickness 0.15)
				)
			)
		)
		(property "Value" "TP_0.75mm_SMD"
			(at 244.475 99.06 0)
			(effects
				(font
					(size 1.27 1.27)
					(thickness 0.15)
				)
				(justify left bottom)
				(hide yes)
			)
		)
		(property "Footprint" "antmicro-footprints:TP_SMD_0.75mm"
			(at 244.475 101.6 0)
			(effects
				(font
					(size 1.27 1.27)
					(thickness 0.15)
				)
				(justify left bottom)
				(hide yes)
			)
		)
		(property "Datasheet" ""
			(at 251.46 107.95 0)
			(effects
				(font
					(size 1.27 1.27)
					(thickness 0.15)
				)
				(justify left bottom)
				(hide yes)
			)
		)
		(property "Description" "SMT test point"
			(at 233.68 95.25 0)
			(effects
				(font
					(size 1.27 1.27)
				)
				(hide yes)
			)
		)
		(property "MPN" ""
			(at 244.475 106.68 0)
			(effects
				(font
					(size 1.27 1.27)
					(thickness 0.15)
				)
				(justify left bottom)
				(hide yes)
			)
		)
		(property "Manufacturer" ""
			(at 244.475 101.6 0)
			(effects
				(font
					(size 1.27 1.27)
					(thickness 0.15)
				)
				(justify left bottom)
				(hide yes)
			)
		)
		(property "Author" "Antmicro"
			(at 244.475 104.14 0)
			(effects
				(font
					(size 1.27 1.27)
					(thickness 0.15)
				)
				(justify left bottom)
				(hide yes)
			)
		)
		(property "License" "Apache-2.0"
			(at 244.475 106.68 0)
			(effects
				(font
					(size 1.27 1.27)
					(thickness 0.15)
				)
				(justify left bottom)
				(hide yes)
			)
		)
		(property "Public" "False"
			(at 243.84 109.22 0)
			(effects
				(font
					(size 1.27 1.27)
				)
				(justify left bottom)
				(hide yes)
			)
		)
		(pin "1"
		)
		(instances
			(project "polarfire-som"
				(path ""
					(reference "TP28")
					(unit 1)
				)
			)
		)
	)
	(symbol
		(lib_id "antmicropower:GND")
		(at 228.6 154.94 0)
		(mirror y)
		(unit 1)
		(exclude_from_sim no)
		(in_bom yes)
		(on_board yes)
		(dnp no)
		(property "Reference" "#PWR0273"
			(at 219.71 157.48 0)
			(effects
				(font
					(size 1.27 1.27)
					(thickness 0.15)
				)
				(justify left bottom)
				(hide yes)
			)
		)
		(property "Value" "GND"
			(at 228.6 158.75 0)
			(effects
				(font
					(size 1.27 1.27)
					(thickness 0.15)
				)
			)
		)
		(property "Footprint" ""
			(at 219.71 162.56 0)
			(effects
				(font
					(size 1.27 1.27)
					(thickness 0.15)
				)
				(justify left bottom)
				(hide yes)
			)
		)
		(property "Datasheet" ""
			(at 219.71 167.64 0)
			(effects
				(font
					(size 1.27 1.27)
					(thickness 0.15)
				)
				(justify left bottom)
				(hide yes)
			)
		)
		(property "Description" ""
			(at 228.6 154.94 0)
			(effects
				(font
					(size 1.27 1.27)
				)
				(hide yes)
			)
		)
		(property "Author" "Antmicro"
			(at 219.71 162.56 0)
			(effects
				(font
					(size 1.27 1.27)
					(thickness 0.15)
				)
				(justify left bottom)
				(hide yes)
			)
		)
		(property "License" "Apache-2.0"
			(at 219.71 165.1 0)
			(effects
				(font
					(size 1.27 1.27)
					(thickness 0.15)
				)
				(justify left bottom)
				(hide yes)
			)
		)
		(pin "1"
		)
		(instances
			(project "polarfire-som"
				(path ""
					(reference "#PWR0273")
					(unit 1)
				)
			)
		)
	)
	(symbol
		(lib_id "antmicroFixedInductors:L_2u2_1.2A_0603")
		(at 166.37 90.17 0)
		(unit 1)
		(exclude_from_sim no)
		(in_bom yes)
		(on_board yes)
		(dnp no)
		(fields_autoplaced yes)
		(property "Reference" "L6"
			(at 168.91 85.09 0)
			(effects
				(font
					(size 1.27 1.27)
					(thickness 0.15)
				)
			)
		)
		(property "Value" "L_2u2_1.2A_0603"
			(at 180.34 92.71 0)
			(effects
				(font
					(size 1.27 1.27)
					(thickness 0.15)
				)
				(justify left bottom)
				(hide yes)
			)
		)
		(property "Footprint" "antmicro-footprints:L_0603_1608Metric"
			(at 180.34 97.79 0)
			(effects
				(font
					(size 1.27 1.27)
					(thickness 0.15)
				)
				(justify left bottom)
				(hide yes)
			)
		)
		(property "Datasheet" "https://www.mouser.com/datasheet/2/3/AOTA_B160808S-3224144.pdf"
			(at 180.34 100.33 0)
			(effects
				(font
					(size 1.27 1.27)
					(thickness 0.15)
				)
				(justify left bottom)
				(hide yes)
			)
		)
		(property "Description" "Wirewound Inductor, 2.2 µH, 240 mOhm, 40 MHz, 1.2 A, 0603 [1608 Metric]"
			(at 166.37 90.17 0)
			(effects
				(font
					(size 1.27 1.27)
				)
				(hide yes)
			)
		)
		(property "Val" "2u2/1.2A"
			(at 168.91 87.63 0)
			(effects
				(font
					(size 1.27 1.27)
					(thickness 0.15)
				)
			)
		)
		(property "Manufacturer" "Abracon"
			(at 180.34 102.87 0)
			(effects
				(font
					(size 1.27 1.27)
					(thickness 0.15)
				)
				(justify left bottom)
				(hide yes)
			)
		)
		(property "MPN" "AOTA-B160808S2R2MT "
			(at 180.34 105.41 0)
			(effects
				(font
					(size 1.27 1.27)
					(thickness 0.15)
				)
				(justify left bottom)
				(hide yes)
			)
		)
		(property "ISat" "1.3 A"
			(at 180.34 106.68 0)
			(effects
				(font
					(size 1.27 1.27)
				)
				(justify left)
				(hide yes)
			)
		)
		(property "IMax" "1.2 A"
			(at 180.34 110.49 0)
			(effects
				(font
					(size 1.27 1.27)
					(thickness 0.15)
				)
				(justify left bottom)
				(hide yes)
			)
		)
		(property "Size" "1.6 x 0.8 x 0.8"
			(at 180.34 113.03 0)
			(effects
				(font
					(size 1.27 1.27)
					(thickness 0.15)
				)
				(justify left bottom)
				(hide yes)
			)
		)
		(property "Author" "Antmicro"
			(at 180.34 115.57 0)
			(effects
				(font
					(size 1.27 1.27)
					(thickness 0.15)
				)
				(justify left bottom)
				(hide yes)
			)
		)
		(property "License" "Apache-2.0"
			(at 180.34 118.11 0)
			(effects
				(font
					(size 1.27 1.27)
					(thickness 0.15)
				)
				(justify left bottom)
				(hide yes)
			)
		)
		(property "Public" ""
			(at 180.34 120.65 0)
			(effects
				(font
					(size 1.27 1.27)
				)
				(justify left bottom)
				(hide yes)
			)
		)
		(pin "2"
		)
		(pin "1"
		)
		(instances
			(project "polarfire-som"
				(path ""
					(reference "L6")
					(unit 1)
				)
			)
		)
	)
)
